(kicad_sch
	(version 20250114)
	(generator "eeschema")
	(generator_version "9.0")
	(paper "A3")
	(title_block
		(title "GMSL Deserializer")
		(date "2025-10-09")
		(rev "1.0.4")
		(company "Antmicro Ltd")
		(comment 1 "www.antmicro.com")
	)
	(text "FFC 5V current limit"
		(exclude_from_sim no)
		(at 323.85 187.96 0)
		(effects
			(font
				(size 4 4)
				(thickness 0.8)
				(bold yes)
			)
			(justify left bottom)
		)
	)
	(text "Power arbiter"
		(exclude_from_sim no)
		(at 56.515 189.865 0)
		(effects
			(font
				(size 4 4)
				(thickness 0.8)
				(bold yes)
			)
			(justify left bottom)
		)
	)
	(text "Buck converter\n12V to 1.8V"
		(exclude_from_sim no)
		(at 294.64 28.575 0)
		(effects
			(font
				(size 4 4)
				(thickness 0.8)
				(bold yes)
			)
			(justify left bottom)
		)
	)
	(text "Boost converter\n5V to 12V"
		(exclude_from_sim no)
		(at 191.135 194.945 0)
		(effects
			(font
				(size 4 4)
				(thickness 0.8)
				(bold yes)
			)
			(justify left bottom)
		)
	)
	(text "Buck converter\n12V to 1.2V"
		(exclude_from_sim no)
		(at 294.64 105.41 0)
		(effects
			(font
				(size 4 4)
				(thickness 0.8)
				(bold yes)
			)
			(justify left bottom)
		)
	)
	(text "PoC circuit"
		(exclude_from_sim no)
		(at 94.615 37.465 0)
		(effects
			(font
				(size 4 4)
				(thickness 0.8)
				(bold yes)
			)
			(justify left bottom)
		)
	)
	(junction
		(at 320.04 132.08)
		(diameter 0)
		(color 0 0 0 0)
	)
	(junction
		(at 50.8 224.79)
		(diameter 0)
		(color 0 0 0 0)
	)
	(junction
		(at 62.23 224.79)
		(diameter 0)
		(color 0 0 0 0)
	)
	(junction
		(at 245.11 232.41)
		(diameter 0)
		(color 0 0 0 0)
	)
	(junction
		(at 31.75 224.79)
		(diameter 0)
		(color 0 0 0 0)
	)
	(junction
		(at 334.01 217.17)
		(diameter 0)
		(color 0 0 0 0)
	)
	(junction
		(at 255.27 232.41)
		(diameter 0)
		(color 0 0 0 0)
	)
	(junction
		(at 327.66 132.08)
		(diameter 0)
		(color 0 0 0 0)
	)
	(junction
		(at 133.35 62.23)
		(diameter 0)
		(color 0 0 0 0)
	)
	(junction
		(at 279.4 60.96)
		(diameter 0)
		(color 0 0 0 0)
	)
	(junction
		(at 110.49 224.79)
		(diameter 0)
		(color 0 0 0 0)
	)
	(junction
		(at 279.4 137.16)
		(diameter 0)
		(color 0 0 0 0)
	)
	(junction
		(at 133.35 140.97)
		(diameter 0)
		(color 0 0 0 0)
	)
	(junction
		(at 327.66 66.04)
		(diameter 0)
		(color 0 0 0 0)
	)
	(junction
		(at 115.57 97.79)
		(diameter 0)
		(color 0 0 0 0)
	)
	(junction
		(at 349.25 132.08)
		(diameter 0)
		(color 0 0 0 0)
	)
	(junction
		(at 237.49 237.49)
		(diameter 0)
		(color 0 0 0 0)
	)
	(junction
		(at 262.89 55.88)
		(diameter 0)
		(color 0 0 0 0)
	)
	(junction
		(at 67.31 224.79)
		(diameter 0)
		(color 0 0 0 0)
	)
	(junction
		(at 340.36 217.17)
		(diameter 0)
		(color 0 0 0 0)
	)
	(junction
		(at 309.88 223.52)
		(diameter 0)
		(color 0 0 0 0)
	)
	(junction
		(at 394.97 217.17)
		(diameter 0)
		(color 0 0 0 0)
	)
	(junction
		(at 102.87 241.3)
		(diameter 0)
		(color 0 0 0 0)
	)
	(junction
		(at 76.2 224.79)
		(diameter 0)
		(color 0 0 0 0)
	)
	(junction
		(at 82.55 224.79)
		(diameter 0)
		(color 0 0 0 0)
	)
	(junction
		(at 331.47 55.88)
		(diameter 0)
		(color 0 0 0 0)
	)
	(junction
		(at 320.04 55.88)
		(diameter 0)
		(color 0 0 0 0)
	)
	(junction
		(at 340.36 132.08)
		(diameter 0)
		(color 0 0 0 0)
	)
	(junction
		(at 115.57 62.23)
		(diameter 0)
		(color 0 0 0 0)
	)
	(junction
		(at 88.9 62.23)
		(diameter 0)
		(color 0 0 0 0)
	)
	(junction
		(at 63.5 254)
		(diameter 0)
		(color 0 0 0 0)
	)
	(junction
		(at 217.17 237.49)
		(diameter 0)
		(color 0 0 0 0)
	)
	(junction
		(at 133.35 114.3)
		(diameter 0)
		(color 0 0 0 0)
	)
	(junction
		(at 115.57 140.97)
		(diameter 0)
		(color 0 0 0 0)
	)
	(junction
		(at 119.38 224.79)
		(diameter 0)
		(color 0 0 0 0)
	)
	(junction
		(at 327.66 142.24)
		(diameter 0)
		(color 0 0 0 0)
	)
	(junction
		(at 237.49 232.41)
		(diameter 0)
		(color 0 0 0 0)
	)
	(junction
		(at 337.82 132.08)
		(diameter 0)
		(color 0 0 0 0)
	)
	(junction
		(at 81.28 114.3)
		(diameter 0)
		(color 0 0 0 0)
	)
	(junction
		(at 250.19 232.41)
		(diameter 0)
		(color 0 0 0 0)
	)
	(junction
		(at 336.55 55.88)
		(diameter 0)
		(color 0 0 0 0)
	)
	(junction
		(at 332.74 132.08)
		(diameter 0)
		(color 0 0 0 0)
	)
	(junction
		(at 67.31 254)
		(diameter 0)
		(color 0 0 0 0)
	)
	(junction
		(at 115.57 149.86)
		(diameter 0)
		(color 0 0 0 0)
	)
	(junction
		(at 115.57 124.46)
		(diameter 0)
		(color 0 0 0 0)
	)
	(junction
		(at 129.54 224.79)
		(diameter 0)
		(color 0 0 0 0)
	)
	(junction
		(at 370.84 132.08)
		(diameter 0)
		(color 0 0 0 0)
	)
	(junction
		(at 388.62 160.02)
		(diameter 0)
		(color 0 0 0 0)
	)
	(junction
		(at 88.9 140.97)
		(diameter 0)
		(color 0 0 0 0)
	)
	(junction
		(at 369.57 55.88)
		(diameter 0)
		(color 0 0 0 0)
	)
	(junction
		(at 363.22 132.08)
		(diameter 0)
		(color 0 0 0 0)
	)
	(junction
		(at 81.28 88.9)
		(diameter 0)
		(color 0 0 0 0)
	)
	(junction
		(at 97.79 88.9)
		(diameter 0)
		(color 0 0 0 0)
	)
	(junction
		(at 363.22 55.88)
		(diameter 0)
		(color 0 0 0 0)
	)
	(junction
		(at 388.62 78.74)
		(diameter 0)
		(color 0 0 0 0)
	)
	(junction
		(at 133.35 88.9)
		(diameter 0)
		(color 0 0 0 0)
	)
	(junction
		(at 217.17 242.57)
		(diameter 0)
		(color 0 0 0 0)
	)
	(junction
		(at 185.42 229.87)
		(diameter 0)
		(color 0 0 0 0)
	)
	(junction
		(at 105.41 224.79)
		(diameter 0)
		(color 0 0 0 0)
	)
	(junction
		(at 97.79 62.23)
		(diameter 0)
		(color 0 0 0 0)
	)
	(junction
		(at 349.25 55.88)
		(diameter 0)
		(color 0 0 0 0)
	)
	(junction
		(at 81.28 140.97)
		(diameter 0)
		(color 0 0 0 0)
	)
	(junction
		(at 115.57 72.39)
		(diameter 0)
		(color 0 0 0 0)
	)
	(junction
		(at 222.25 232.41)
		(diameter 0)
		(color 0 0 0 0)
	)
	(junction
		(at 81.28 224.79)
		(diameter 0)
		(color 0 0 0 0)
	)
	(junction
		(at 340.36 55.88)
		(diameter 0)
		(color 0 0 0 0)
	)
	(junction
		(at 97.79 114.3)
		(diameter 0)
		(color 0 0 0 0)
	)
	(junction
		(at 88.9 88.9)
		(diameter 0)
		(color 0 0 0 0)
	)
	(junction
		(at 50.8 245.11)
		(diameter 0)
		(color 0 0 0 0)
	)
	(junction
		(at 88.9 114.3)
		(diameter 0)
		(color 0 0 0 0)
	)
	(junction
		(at 115.57 114.3)
		(diameter 0)
		(color 0 0 0 0)
	)
	(junction
		(at 100.33 224.79)
		(diameter 0)
		(color 0 0 0 0)
	)
	(junction
		(at 375.92 71.12)
		(diameter 0)
		(color 0 0 0 0)
	)
	(junction
		(at 189.23 229.87)
		(diameter 0)
		(color 0 0 0 0)
	)
	(junction
		(at 81.28 62.23)
		(diameter 0)
		(color 0 0 0 0)
	)
	(junction
		(at 375.92 152.4)
		(diameter 0)
		(color 0 0 0 0)
	)
	(junction
		(at 262.89 132.08)
		(diameter 0)
		(color 0 0 0 0)
	)
	(junction
		(at 97.79 140.97)
		(diameter 0)
		(color 0 0 0 0)
	)
	(junction
		(at 180.34 229.87)
		(diameter 0)
		(color 0 0 0 0)
	)
	(junction
		(at 168.91 229.87)
		(diameter 0)
		(color 0 0 0 0)
	)
	(junction
		(at 115.57 88.9)
		(diameter 0)
		(color 0 0 0 0)
	)
	(junction
		(at 327.66 55.88)
		(diameter 0)
		(color 0 0 0 0)
	)
	(wire
		(pts
			(xy 99.06 241.3) (xy 102.87 241.3)
		)
		(stroke
			(width 0)
			(type default)
		)
	)
	(wire
		(pts
			(xy 121.92 72.39) (xy 115.57 72.39)
		)
		(stroke
			(width 0)
			(type default)
		)
	)
	(wire
		(pts
			(xy 214.63 237.49) (xy 217.17 237.49)
		)
		(stroke
			(width 0)
			(type default)
		)
	)
	(wire
		(pts
			(xy 189.23 231.14) (xy 189.23 229.87)
		)
		(stroke
			(width 0)
			(type default)
		)
	)
	(wire
		(pts
			(xy 388.62 80.01) (xy 388.62 78.74)
		)
		(stroke
			(width 0)
			(type default)
		)
	)
	(wire
		(pts
			(xy 217.17 250.19) (xy 217.17 251.46)
		)
		(stroke
			(width 0)
			(type default)
		)
	)
	(wire
		(pts
			(xy 228.6 237.49) (xy 237.49 237.49)
		)
		(stroke
			(width 0)
			(type default)
		)
	)
	(wire
		(pts
			(xy 388.62 46.99) (xy 388.62 48.26)
		)
		(stroke
			(width 0)
			(type default)
		)
	)
	(wire
		(pts
			(xy 316.23 137.16) (xy 320.04 137.16)
		)
		(stroke
			(width 0)
			(type default)
		)
	)
	(wire
		(pts
			(xy 349.25 149.86) (xy 349.25 151.13)
		)
		(stroke
			(width 0)
			(type default)
		)
	)
	(wire
		(pts
			(xy 222.25 220.98) (xy 222.25 232.41)
		)
		(stroke
			(width 0)
			(type default)
		)
	)
	(wire
		(pts
			(xy 105.41 223.52) (xy 105.41 224.79)
		)
		(stroke
			(width 0)
			(type default)
		)
	)
	(wire
		(pts
			(xy 388.62 142.24) (xy 388.62 144.78)
		)
		(stroke
			(width 0)
			(type default)
		)
	)
	(wire
		(pts
			(xy 180.34 229.87) (xy 185.42 229.87)
		)
		(stroke
			(width 0)
			(type default)
		)
	)
	(wire
		(pts
			(xy 81.28 62.23) (xy 88.9 62.23)
		)
		(stroke
			(width 0)
			(type default)
		)
	)
	(wire
		(pts
			(xy 76.2 224.79) (xy 81.28 224.79)
		)
		(stroke
			(width 0)
			(type default)
		)
	)
	(wire
		(pts
			(xy 82.55 210.82) (xy 82.55 224.79)
		)
		(stroke
			(width 0)
			(type default)
		)
	)
	(wire
		(pts
			(xy 279.4 137.16) (xy 288.29 137.16)
		)
		(stroke
			(width 0)
			(type default)
		)
	)
	(wire
		(pts
			(xy 287.02 142.24) (xy 288.29 142.24)
		)
		(stroke
			(width 0)
			(type default)
		)
	)
	(wire
		(pts
			(xy 144.78 62.23) (xy 157.48 62.23)
		)
		(stroke
			(width 0)
			(type default)
		)
	)
	(wire
		(pts
			(xy 133.35 149.86) (xy 133.35 140.97)
		)
		(stroke
			(width 0)
			(type default)
		)
	)
	(wire
		(pts
			(xy 50.8 242.57) (xy 50.8 245.11)
		)
		(stroke
			(width 0)
			(type default)
		)
	)
	(wire
		(pts
			(xy 50.8 224.79) (xy 50.8 237.49)
		)
		(stroke
			(width 0)
			(type default)
		)
	)
	(wire
		(pts
			(xy 279.4 60.96) (xy 288.29 60.96)
		)
		(stroke
			(width 0)
			(type default)
		)
	)
	(wire
		(pts
			(xy 334.01 217.17) (xy 340.36 217.17)
		)
		(stroke
			(width 0)
			(type default)
		)
	)
	(wire
		(pts
			(xy 255.27 232.41) (xy 259.08 232.41)
		)
		(stroke
			(width 0)
			(type default)
		)
	)
	(wire
		(pts
			(xy 370.84 130.81) (xy 370.84 132.08)
		)
		(stroke
			(width 0)
			(type default)
		)
	)
	(wire
		(pts
			(xy 279.4 128.27) (xy 279.4 137.16)
		)
		(stroke
			(width 0)
			(type default)
		)
	)
	(wire
		(pts
			(xy 81.28 140.97) (xy 88.9 140.97)
		)
		(stroke
			(width 0)
			(type default)
		)
	)
	(wire
		(pts
			(xy 81.28 118.11) (xy 81.28 114.3)
		)
		(stroke
			(width 0)
			(type default)
		)
	)
	(wire
		(pts
			(xy 308.61 132.08) (xy 320.04 132.08)
		)
		(stroke
			(width 0)
			(type default)
		)
	)
	(wire
		(pts
			(xy 100.33 224.79) (xy 100.33 238.76)
		)
		(stroke
			(width 0)
			(type default)
		)
	)
	(wire
		(pts
			(xy 129.54 224.79) (xy 129.54 227.33)
		)
		(stroke
			(width 0)
			(type default)
		)
	)
	(wire
		(pts
			(xy 102.87 232.41) (xy 102.87 241.3)
		)
		(stroke
			(width 0)
			(type default)
		)
	)
	(wire
		(pts
			(xy 81.28 224.79) (xy 82.55 224.79)
		)
		(stroke
			(width 0)
			(type default)
		)
	)
	(wire
		(pts
			(xy 195.58 229.87) (xy 189.23 229.87)
		)
		(stroke
			(width 0)
			(type default)
		)
	)
	(wire
		(pts
			(xy 115.57 97.79) (xy 115.57 88.9)
		)
		(stroke
			(width 0)
			(type default)
		)
	)
	(wire
		(pts
			(xy 168.91 88.9) (xy 162.56 88.9)
		)
		(stroke
			(width 0)
			(type default)
		)
	)
	(wire
		(pts
			(xy 115.57 88.9) (xy 109.22 88.9)
		)
		(stroke
			(width 0)
			(type default)
		)
	)
	(wire
		(pts
			(xy 110.49 223.52) (xy 110.49 224.79)
		)
		(stroke
			(width 0)
			(type default)
		)
	)
	(wire
		(pts
			(xy 88.9 149.86) (xy 88.9 148.59)
		)
		(stroke
			(width 0)
			(type default)
		)
	)
	(wire
		(pts
			(xy 375.92 160.02) (xy 388.62 160.02)
		)
		(stroke
			(width 0)
			(type default)
		)
	)
	(wire
		(pts
			(xy 97.79 224.79) (xy 100.33 224.79)
		)
		(stroke
			(width 0)
			(type default)
		)
	)
	(wire
		(pts
			(xy 127 149.86) (xy 133.35 149.86)
		)
		(stroke
			(width 0)
			(type default)
		)
	)
	(wire
		(pts
			(xy 81.28 143.51) (xy 81.28 140.97)
		)
		(stroke
			(width 0)
			(type default)
		)
	)
	(wire
		(pts
			(xy 81.28 66.04) (xy 81.28 62.23)
		)
		(stroke
			(width 0)
			(type default)
		)
	)
	(wire
		(pts
			(xy 127 124.46) (xy 133.35 124.46)
		)
		(stroke
			(width 0)
			(type default)
		)
	)
	(wire
		(pts
			(xy 50.8 245.11) (xy 57.15 245.11)
		)
		(stroke
			(width 0)
			(type default)
		)
	)
	(wire
		(pts
			(xy 127 72.39) (xy 133.35 72.39)
		)
		(stroke
			(width 0)
			(type default)
		)
	)
	(wire
		(pts
			(xy 82.55 224.79) (xy 87.63 224.79)
		)
		(stroke
			(width 0)
			(type default)
		)
	)
	(wire
		(pts
			(xy 62.23 224.79) (xy 67.31 224.79)
		)
		(stroke
			(width 0)
			(type default)
		)
	)
	(wire
		(pts
			(xy 320.04 132.08) (xy 321.31 132.08)
		)
		(stroke
			(width 0)
			(type default)
		)
	)
	(wire
		(pts
			(xy 349.25 72.39) (xy 349.25 73.66)
		)
		(stroke
			(width 0)
			(type default)
		)
	)
	(wire
		(pts
			(xy 168.91 62.23) (xy 162.56 62.23)
		)
		(stroke
			(width 0)
			(type default)
		)
	)
	(wire
		(pts
			(xy 88.9 91.44) (xy 88.9 88.9)
		)
		(stroke
			(width 0)
			(type default)
		)
	)
	(wire
		(pts
			(xy 180.34 228.6) (xy 180.34 229.87)
		)
		(stroke
			(width 0)
			(type default)
		)
	)
	(wire
		(pts
			(xy 115.57 88.9) (xy 121.92 88.9)
		)
		(stroke
			(width 0)
			(type default)
		)
	)
	(wire
		(pts
			(xy 81.28 238.76) (xy 82.55 238.76)
		)
		(stroke
			(width 0)
			(type default)
		)
	)
	(wire
		(pts
			(xy 375.92 158.75) (xy 375.92 160.02)
		)
		(stroke
			(width 0)
			(type default)
		)
	)
	(wire
		(pts
			(xy 237.49 232.41) (xy 245.11 232.41)
		)
		(stroke
			(width 0)
			(type default)
		)
	)
	(wire
		(pts
			(xy 217.17 237.49) (xy 217.17 242.57)
		)
		(stroke
			(width 0)
			(type default)
		)
	)
	(wire
		(pts
			(xy 340.36 217.17) (xy 359.41 217.17)
		)
		(stroke
			(width 0)
			(type default)
		)
	)
	(wire
		(pts
			(xy 214.63 232.41) (xy 222.25 232.41)
		)
		(stroke
			(width 0)
			(type default)
		)
	)
	(wire
		(pts
			(xy 388.62 53.34) (xy 388.62 55.88)
		)
		(stroke
			(width 0)
			(type default)
		)
	)
	(wire
		(pts
			(xy 133.35 124.46) (xy 133.35 114.3)
		)
		(stroke
			(width 0)
			(type default)
		)
	)
	(wire
		(pts
			(xy 262.89 137.16) (xy 262.89 132.08)
		)
		(stroke
			(width 0)
			(type default)
		)
	)
	(wire
		(pts
			(xy 340.36 72.39) (xy 340.36 73.66)
		)
		(stroke
			(width 0)
			(type default)
		)
	)
	(polyline
		(pts
			(xy 231.14 12.7) (xy 231.14 168.91)
		)
		(stroke
			(width 0)
			(type dash)
		)
	)
	(wire
		(pts
			(xy 88.9 88.9) (xy 97.79 88.9)
		)
		(stroke
			(width 0)
			(type default)
		)
	)
	(wire
		(pts
			(xy 95.25 232.41) (xy 102.87 232.41)
		)
		(stroke
			(width 0)
			(type default)
		)
	)
	(wire
		(pts
			(xy 327.66 55.88) (xy 327.66 57.15)
		)
		(stroke
			(width 0)
			(type default)
		)
	)
	(polyline
		(pts
			(xy 147.32 168.91) (xy 147.32 284.48)
		)
		(stroke
			(width 0)
			(type dash)
		)
	)
	(wire
		(pts
			(xy 262.89 130.81) (xy 262.89 132.08)
		)
		(stroke
			(width 0)
			(type default)
		)
	)
	(wire
		(pts
			(xy 217.17 237.49) (xy 223.52 237.49)
		)
		(stroke
			(width 0)
			(type default)
		)
	)
	(wire
		(pts
			(xy 388.62 128.27) (xy 388.62 129.54)
		)
		(stroke
			(width 0)
			(type default)
		)
	)
	(wire
		(pts
			(xy 262.89 55.88) (xy 288.29 55.88)
		)
		(stroke
			(width 0)
			(type default)
		)
	)
	(wire
		(pts
			(xy 358.14 55.88) (xy 363.22 55.88)
		)
		(stroke
			(width 0)
			(type default)
		)
	)
	(wire
		(pts
			(xy 97.79 114.3) (xy 104.14 114.3)
		)
		(stroke
			(width 0)
			(type default)
		)
	)
	(wire
		(pts
			(xy 308.61 137.16) (xy 311.15 137.16)
		)
		(stroke
			(width 0)
			(type default)
		)
	)
	(wire
		(pts
			(xy 327.66 66.04) (xy 327.66 67.31)
		)
		(stroke
			(width 0)
			(type default)
		)
	)
	(wire
		(pts
			(xy 331.47 55.88) (xy 336.55 55.88)
		)
		(stroke
			(width 0)
			(type default)
		)
	)
	(wire
		(pts
			(xy 144.78 140.97) (xy 157.48 140.97)
		)
		(stroke
			(width 0)
			(type default)
		)
	)
	(wire
		(pts
			(xy 88.9 143.51) (xy 88.9 140.97)
		)
		(stroke
			(width 0)
			(type default)
		)
	)
	(wire
		(pts
			(xy 115.57 114.3) (xy 121.92 114.3)
		)
		(stroke
			(width 0)
			(type default)
		)
	)
	(wire
		(pts
			(xy 121.92 149.86) (xy 115.57 149.86)
		)
		(stroke
			(width 0)
			(type default)
		)
	)
	(wire
		(pts
			(xy 31.75 236.22) (xy 31.75 238.76)
		)
		(stroke
			(width 0)
			(type default)
		)
	)
	(wire
		(pts
			(xy 97.79 72.39) (xy 97.79 62.23)
		)
		(stroke
			(width 0)
			(type default)
		)
	)
	(wire
		(pts
			(xy 374.65 217.17) (xy 394.97 217.17)
		)
		(stroke
			(width 0)
			(type default)
		)
	)
	(wire
		(pts
			(xy 337.82 132.08) (xy 340.36 132.08)
		)
		(stroke
			(width 0)
			(type default)
		)
	)
	(wire
		(pts
			(xy 81.28 91.44) (xy 81.28 88.9)
		)
		(stroke
			(width 0)
			(type default)
		)
	)
	(wire
		(pts
			(xy 375.92 152.4) (xy 382.27 152.4)
		)
		(stroke
			(width 0)
			(type default)
		)
	)
	(wire
		(pts
			(xy 50.8 254) (xy 63.5 254)
		)
		(stroke
			(width 0)
			(type default)
		)
	)
	(wire
		(pts
			(xy 327.66 149.86) (xy 327.66 151.13)
		)
		(stroke
			(width 0)
			(type default)
		)
	)
	(wire
		(pts
			(xy 287.02 66.04) (xy 288.29 66.04)
		)
		(stroke
			(width 0)
			(type default)
		)
	)
	(polyline
		(pts
			(xy 12.7 168.91) (xy 231.14 168.91)
		)
		(stroke
			(width 0)
			(type dash)
		)
	)
	(wire
		(pts
			(xy 50.8 245.11) (xy 50.8 247.65)
		)
		(stroke
			(width 0)
			(type default)
		)
	)
	(wire
		(pts
			(xy 119.38 223.52) (xy 119.38 224.79)
		)
		(stroke
			(width 0)
			(type default)
		)
	)
	(wire
		(pts
			(xy 367.03 152.4) (xy 375.92 152.4)
		)
		(stroke
			(width 0)
			(type default)
		)
	)
	(wire
		(pts
			(xy 375.92 71.12) (xy 382.27 71.12)
		)
		(stroke
			(width 0)
			(type default)
		)
	)
	(wire
		(pts
			(xy 332.74 132.08) (xy 337.82 132.08)
		)
		(stroke
			(width 0)
			(type default)
		)
	)
	(wire
		(pts
			(xy 279.4 44.45) (xy 279.4 45.72)
		)
		(stroke
			(width 0)
			(type default)
		)
	)
	(wire
		(pts
			(xy 102.87 248.92) (xy 102.87 250.19)
		)
		(stroke
			(width 0)
			(type default)
		)
	)
	(wire
		(pts
			(xy 133.35 97.79) (xy 133.35 88.9)
		)
		(stroke
			(width 0)
			(type default)
		)
	)
	(wire
		(pts
			(xy 81.28 248.92) (xy 81.28 250.19)
		)
		(stroke
			(width 0)
			(type default)
		)
	)
	(wire
		(pts
			(xy 81.28 88.9) (xy 88.9 88.9)
		)
		(stroke
			(width 0)
			(type default)
		)
	)
	(wire
		(pts
			(xy 375.92 78.74) (xy 388.62 78.74)
		)
		(stroke
			(width 0)
			(type default)
		)
	)
	(wire
		(pts
			(xy 279.4 143.51) (xy 279.4 144.78)
		)
		(stroke
			(width 0)
			(type default)
		)
	)
	(wire
		(pts
			(xy 309.88 222.25) (xy 309.88 223.52)
		)
		(stroke
			(width 0)
			(type default)
		)
	)
	(wire
		(pts
			(xy 81.28 87.63) (xy 81.28 88.9)
		)
		(stroke
			(width 0)
			(type default)
		)
	)
	(wire
		(pts
			(xy 287.02 67.31) (xy 287.02 66.04)
		)
		(stroke
			(width 0)
			(type default)
		)
	)
	(wire
		(pts
			(xy 369.57 54.61) (xy 369.57 55.88)
		)
		(stroke
			(width 0)
			(type default)
		)
	)
	(wire
		(pts
			(xy 340.36 149.86) (xy 340.36 151.13)
		)
		(stroke
			(width 0)
			(type default)
		)
	)
	(wire
		(pts
			(xy 332.74 132.08) (xy 327.66 132.08)
		)
		(stroke
			(width 0)
			(type default)
		)
	)
	(wire
		(pts
			(xy 168.91 241.3) (xy 168.91 243.84)
		)
		(stroke
			(width 0)
			(type default)
		)
	)
	(wire
		(pts
			(xy 394.97 217.17) (xy 394.97 219.71)
		)
		(stroke
			(width 0)
			(type default)
		)
	)
	(wire
		(pts
			(xy 129.54 240.03) (xy 129.54 241.3)
		)
		(stroke
			(width 0)
			(type default)
		)
	)
	(wire
		(pts
			(xy 88.9 66.04) (xy 88.9 62.23)
		)
		(stroke
			(width 0)
			(type default)
		)
	)
	(wire
		(pts
			(xy 97.79 88.9) (xy 104.14 88.9)
		)
		(stroke
			(width 0)
			(type default)
		)
	)
	(wire
		(pts
			(xy 82.55 241.3) (xy 81.28 241.3)
		)
		(stroke
			(width 0)
			(type default)
		)
	)
	(wire
		(pts
			(xy 340.36 217.17) (xy 340.36 218.44)
		)
		(stroke
			(width 0)
			(type default)
		)
	)
	(wire
		(pts
			(xy 262.89 54.61) (xy 262.89 55.88)
		)
		(stroke
			(width 0)
			(type default)
		)
	)
	(wire
		(pts
			(xy 349.25 144.78) (xy 349.25 132.08)
		)
		(stroke
			(width 0)
			(type default)
		)
	)
	(wire
		(pts
			(xy 63.5 247.65) (xy 63.5 254)
		)
		(stroke
			(width 0)
			(type default)
		)
	)
	(wire
		(pts
			(xy 332.74 130.81) (xy 332.74 132.08)
		)
		(stroke
			(width 0)
			(type default)
		)
	)
	(wire
		(pts
			(xy 349.25 132.08) (xy 340.36 132.08)
		)
		(stroke
			(width 0)
			(type default)
		)
	)
	(wire
		(pts
			(xy 275.59 240.03) (xy 275.59 251.46)
		)
		(stroke
			(width 0)
			(type default)
		)
	)
	(wire
		(pts
			(xy 262.89 64.77) (xy 262.89 67.31)
		)
		(stroke
			(width 0)
			(type default)
		)
	)
	(wire
		(pts
			(xy 133.35 88.9) (xy 127 88.9)
		)
		(stroke
			(width 0)
			(type default)
		)
	)
	(wire
		(pts
			(xy 245.11 238.76) (xy 245.11 240.03)
		)
		(stroke
			(width 0)
			(type default)
		)
	)
	(wire
		(pts
			(xy 72.39 252.73) (xy 72.39 254)
		)
		(stroke
			(width 0)
			(type default)
		)
	)
	(wire
		(pts
			(xy 115.57 62.23) (xy 121.92 62.23)
		)
		(stroke
			(width 0)
			(type default)
		)
	)
	(wire
		(pts
			(xy 346.71 219.71) (xy 359.41 219.71)
		)
		(stroke
			(width 0)
			(type default)
		)
	)
	(wire
		(pts
			(xy 377.19 130.81) (xy 377.19 132.08)
		)
		(stroke
			(width 0)
			(type default)
		)
	)
	(wire
		(pts
			(xy 262.89 132.08) (xy 288.29 132.08)
		)
		(stroke
			(width 0)
			(type default)
		)
	)
	(wire
		(pts
			(xy 185.42 228.6) (xy 185.42 229.87)
		)
		(stroke
			(width 0)
			(type default)
		)
	)
	(wire
		(pts
			(xy 196.85 238.76) (xy 189.23 238.76)
		)
		(stroke
			(width 0)
			(type default)
		)
	)
	(wire
		(pts
			(xy 374.65 219.71) (xy 387.35 219.71)
		)
		(stroke
			(width 0)
			(type default)
		)
	)
	(wire
		(pts
			(xy 279.4 60.96) (xy 279.4 62.23)
		)
		(stroke
			(width 0)
			(type default)
		)
	)
	(wire
		(pts
			(xy 144.78 88.9) (xy 157.48 88.9)
		)
		(stroke
			(width 0)
			(type default)
		)
	)
	(polyline
		(pts
			(xy 231.14 168.91) (xy 408.94 168.91)
		)
		(stroke
			(width 0)
			(type dash)
		)
	)
	(wire
		(pts
			(xy 340.36 67.31) (xy 340.36 55.88)
		)
		(stroke
			(width 0)
			(type default)
		)
	)
	(wire
		(pts
			(xy 121.92 97.79) (xy 115.57 97.79)
		)
		(stroke
			(width 0)
			(type default)
		)
	)
	(wire
		(pts
			(xy 255.27 231.14) (xy 255.27 232.41)
		)
		(stroke
			(width 0)
			(type default)
		)
	)
	(wire
		(pts
			(xy 67.31 254) (xy 67.31 252.73)
		)
		(stroke
			(width 0)
			(type default)
		)
	)
	(wire
		(pts
			(xy 370.84 132.08) (xy 377.19 132.08)
		)
		(stroke
			(width 0)
			(type default)
		)
	)
	(wire
		(pts
			(xy 388.62 78.74) (xy 388.62 73.66)
		)
		(stroke
			(width 0)
			(type default)
		)
	)
	(wire
		(pts
			(xy 327.66 72.39) (xy 327.66 73.66)
		)
		(stroke
			(width 0)
			(type default)
		)
	)
	(wire
		(pts
			(xy 199.39 232.41) (xy 195.58 232.41)
		)
		(stroke
			(width 0)
			(type default)
		)
	)
	(wire
		(pts
			(xy 144.78 114.3) (xy 157.48 114.3)
		)
		(stroke
			(width 0)
			(type default)
		)
	)
	(wire
		(pts
			(xy 81.28 241.3) (xy 81.28 243.84)
		)
		(stroke
			(width 0)
			(type default)
		)
	)
	(wire
		(pts
			(xy 81.28 113.03) (xy 81.28 114.3)
		)
		(stroke
			(width 0)
			(type default)
		)
	)
	(wire
		(pts
			(xy 109.22 124.46) (xy 115.57 124.46)
		)
		(stroke
			(width 0)
			(type default)
		)
	)
	(wire
		(pts
			(xy 198.12 238.76) (xy 198.12 237.49)
		)
		(stroke
			(width 0)
			(type default)
		)
	)
	(wire
		(pts
			(xy 53.34 233.68) (xy 63.5 233.68)
		)
		(stroke
			(width 0)
			(type default)
		)
	)
	(wire
		(pts
			(xy 237.49 242.57) (xy 237.49 237.49)
		)
		(stroke
			(width 0)
			(type default)
		)
	)
	(wire
		(pts
			(xy 275.59 264.16) (xy 275.59 265.43)
		)
		(stroke
			(width 0)
			(type default)
		)
	)
	(wire
		(pts
			(xy 340.36 144.78) (xy 340.36 132.08)
		)
		(stroke
			(width 0)
			(type default)
		)
	)
	(wire
		(pts
			(xy 50.8 254) (xy 50.8 252.73)
		)
		(stroke
			(width 0)
			(type default)
		)
	)
	(wire
		(pts
			(xy 217.17 242.57) (xy 222.25 242.57)
		)
		(stroke
			(width 0)
			(type default)
		)
	)
	(wire
		(pts
			(xy 336.55 55.88) (xy 340.36 55.88)
		)
		(stroke
			(width 0)
			(type default)
		)
	)
	(wire
		(pts
			(xy 349.25 132.08) (xy 353.06 132.08)
		)
		(stroke
			(width 0)
			(type default)
		)
	)
	(wire
		(pts
			(xy 168.91 228.6) (xy 168.91 229.87)
		)
		(stroke
			(width 0)
			(type default)
		)
	)
	(wire
		(pts
			(xy 105.41 224.79) (xy 110.49 224.79)
		)
		(stroke
			(width 0)
			(type default)
		)
	)
	(wire
		(pts
			(xy 394.97 215.9) (xy 394.97 217.17)
		)
		(stroke
			(width 0)
			(type default)
		)
	)
	(wire
		(pts
			(xy 100.33 224.79) (xy 105.41 224.79)
		)
		(stroke
			(width 0)
			(type default)
		)
	)
	(wire
		(pts
			(xy 121.92 124.46) (xy 115.57 124.46)
		)
		(stroke
			(width 0)
			(type default)
		)
	)
	(wire
		(pts
			(xy 388.62 161.29) (xy 388.62 160.02)
		)
		(stroke
			(width 0)
			(type default)
		)
	)
	(wire
		(pts
			(xy 367.03 71.12) (xy 375.92 71.12)
		)
		(stroke
			(width 0)
			(type default)
		)
	)
	(wire
		(pts
			(xy 95.25 231.14) (xy 95.25 232.41)
		)
		(stroke
			(width 0)
			(type default)
		)
	)
	(wire
		(pts
			(xy 394.97 224.79) (xy 394.97 226.06)
		)
		(stroke
			(width 0)
			(type default)
		)
	)
	(wire
		(pts
			(xy 326.39 132.08) (xy 327.66 132.08)
		)
		(stroke
			(width 0)
			(type default)
		)
	)
	(wire
		(pts
			(xy 227.33 242.57) (xy 237.49 242.57)
		)
		(stroke
			(width 0)
			(type default)
		)
	)
	(wire
		(pts
			(xy 349.25 55.88) (xy 340.36 55.88)
		)
		(stroke
			(width 0)
			(type default)
		)
	)
	(wire
		(pts
			(xy 168.91 229.87) (xy 180.34 229.87)
		)
		(stroke
			(width 0)
			(type default)
		)
	)
	(wire
		(pts
			(xy 316.23 60.96) (xy 320.04 60.96)
		)
		(stroke
			(width 0)
			(type default)
		)
	)
	(wire
		(pts
			(xy 309.88 215.9) (xy 309.88 217.17)
		)
		(stroke
			(width 0)
			(type default)
		)
	)
	(wire
		(pts
			(xy 327.66 132.08) (xy 327.66 133.35)
		)
		(stroke
			(width 0)
			(type default)
		)
	)
	(wire
		(pts
			(xy 375.92 54.61) (xy 375.92 55.88)
		)
		(stroke
			(width 0)
			(type default)
		)
	)
	(wire
		(pts
			(xy 369.57 55.88) (xy 375.92 55.88)
		)
		(stroke
			(width 0)
			(type default)
		)
	)
	(wire
		(pts
			(xy 388.62 154.94) (xy 388.62 160.02)
		)
		(stroke
			(width 0)
			(type default)
		)
	)
	(wire
		(pts
			(xy 279.4 137.16) (xy 279.4 138.43)
		)
		(stroke
			(width 0)
			(type default)
		)
	)
	(wire
		(pts
			(xy 327.66 55.88) (xy 331.47 55.88)
		)
		(stroke
			(width 0)
			(type default)
		)
	)
	(wire
		(pts
			(xy 67.31 224.79) (xy 76.2 224.79)
		)
		(stroke
			(width 0)
			(type default)
		)
	)
	(wire
		(pts
			(xy 245.11 232.41) (xy 245.11 233.68)
		)
		(stroke
			(width 0)
			(type default)
		)
	)
	(polyline
		(pts
			(xy 231.14 88.9) (xy 408.94 88.9)
		)
		(stroke
			(width 0)
			(type dash)
		)
	)
	(wire
		(pts
			(xy 168.91 140.97) (xy 162.56 140.97)
		)
		(stroke
			(width 0)
			(type default)
		)
	)
	(wire
		(pts
			(xy 270.51 232.41) (xy 270.51 229.87)
		)
		(stroke
			(width 0)
			(type default)
		)
	)
	(wire
		(pts
			(xy 209.55 220.98) (xy 222.25 220.98)
		)
		(stroke
			(width 0)
			(type default)
		)
	)
	(wire
		(pts
			(xy 375.92 77.47) (xy 375.92 78.74)
		)
		(stroke
			(width 0)
			(type default)
		)
	)
	(wire
		(pts
			(xy 245.11 232.41) (xy 250.19 232.41)
		)
		(stroke
			(width 0)
			(type default)
		)
	)
	(wire
		(pts
			(xy 88.9 97.79) (xy 88.9 96.52)
		)
		(stroke
			(width 0)
			(type default)
		)
	)
	(wire
		(pts
			(xy 375.92 71.12) (xy 375.92 72.39)
		)
		(stroke
			(width 0)
			(type default)
		)
	)
	(wire
		(pts
			(xy 88.9 62.23) (xy 97.79 62.23)
		)
		(stroke
			(width 0)
			(type default)
		)
	)
	(wire
		(pts
			(xy 308.61 55.88) (xy 320.04 55.88)
		)
		(stroke
			(width 0)
			(type default)
		)
	)
	(wire
		(pts
			(xy 320.04 137.16) (xy 320.04 132.08)
		)
		(stroke
			(width 0)
			(type default)
		)
	)
	(wire
		(pts
			(xy 104.14 97.79) (xy 97.79 97.79)
		)
		(stroke
			(width 0)
			(type default)
		)
	)
	(wire
		(pts
			(xy 30.48 224.79) (xy 31.75 224.79)
		)
		(stroke
			(width 0)
			(type default)
		)
	)
	(wire
		(pts
			(xy 97.79 124.46) (xy 97.79 114.3)
		)
		(stroke
			(width 0)
			(type default)
		)
	)
	(wire
		(pts
			(xy 99.06 238.76) (xy 100.33 238.76)
		)
		(stroke
			(width 0)
			(type default)
		)
	)
	(wire
		(pts
			(xy 189.23 238.76) (xy 189.23 236.22)
		)
		(stroke
			(width 0)
			(type default)
		)
	)
	(wire
		(pts
			(xy 349.25 55.88) (xy 353.06 55.88)
		)
		(stroke
			(width 0)
			(type default)
		)
	)
	(wire
		(pts
			(xy 133.35 114.3) (xy 139.7 114.3)
		)
		(stroke
			(width 0)
			(type default)
		)
	)
	(wire
		(pts
			(xy 88.9 114.3) (xy 97.79 114.3)
		)
		(stroke
			(width 0)
			(type default)
		)
	)
	(wire
		(pts
			(xy 115.57 114.3) (xy 109.22 114.3)
		)
		(stroke
			(width 0)
			(type default)
		)
	)
	(wire
		(pts
			(xy 363.22 132.08) (xy 370.84 132.08)
		)
		(stroke
			(width 0)
			(type default)
		)
	)
	(wire
		(pts
			(xy 104.14 149.86) (xy 97.79 149.86)
		)
		(stroke
			(width 0)
			(type default)
		)
	)
	(wire
		(pts
			(xy 129.54 232.41) (xy 129.54 234.95)
		)
		(stroke
			(width 0)
			(type default)
		)
	)
	(wire
		(pts
			(xy 97.79 140.97) (xy 104.14 140.97)
		)
		(stroke
			(width 0)
			(type default)
		)
	)
	(wire
		(pts
			(xy 287.02 144.78) (xy 287.02 142.24)
		)
		(stroke
			(width 0)
			(type default)
		)
	)
	(wire
		(pts
			(xy 81.28 97.79) (xy 81.28 96.52)
		)
		(stroke
			(width 0)
			(type default)
		)
	)
	(wire
		(pts
			(xy 180.34 229.87) (xy 180.34 231.14)
		)
		(stroke
			(width 0)
			(type default)
		)
	)
	(wire
		(pts
			(xy 133.35 88.9) (xy 139.7 88.9)
		)
		(stroke
			(width 0)
			(type default)
		)
	)
	(wire
		(pts
			(xy 133.35 62.23) (xy 139.7 62.23)
		)
		(stroke
			(width 0)
			(type default)
		)
	)
	(wire
		(pts
			(xy 387.35 224.79) (xy 387.35 226.06)
		)
		(stroke
			(width 0)
			(type default)
		)
	)
	(wire
		(pts
			(xy 308.61 142.24) (xy 327.66 142.24)
		)
		(stroke
			(width 0)
			(type default)
		)
	)
	(wire
		(pts
			(xy 308.61 60.96) (xy 311.15 60.96)
		)
		(stroke
			(width 0)
			(type default)
		)
	)
	(wire
		(pts
			(xy 275.59 256.54) (xy 275.59 259.08)
		)
		(stroke
			(width 0)
			(type default)
		)
	)
	(wire
		(pts
			(xy 346.71 208.28) (xy 346.71 209.55)
		)
		(stroke
			(width 0)
			(type default)
		)
	)
	(wire
		(pts
			(xy 109.22 149.86) (xy 115.57 149.86)
		)
		(stroke
			(width 0)
			(type default)
		)
	)
	(wire
		(pts
			(xy 115.57 140.97) (xy 109.22 140.97)
		)
		(stroke
			(width 0)
			(type default)
		)
	)
	(wire
		(pts
			(xy 334.01 224.79) (xy 334.01 223.52)
		)
		(stroke
			(width 0)
			(type default)
		)
	)
	(wire
		(pts
			(xy 196.85 234.95) (xy 196.85 238.76)
		)
		(stroke
			(width 0)
			(type default)
		)
	)
	(wire
		(pts
			(xy 62.23 223.52) (xy 62.23 224.79)
		)
		(stroke
			(width 0)
			(type default)
		)
	)
	(wire
		(pts
			(xy 133.35 140.97) (xy 139.7 140.97)
		)
		(stroke
			(width 0)
			(type default)
		)
	)
	(wire
		(pts
			(xy 115.57 149.86) (xy 115.57 140.97)
		)
		(stroke
			(width 0)
			(type default)
		)
	)
	(wire
		(pts
			(xy 109.22 97.79) (xy 115.57 97.79)
		)
		(stroke
			(width 0)
			(type default)
		)
	)
	(wire
		(pts
			(xy 195.58 232.41) (xy 195.58 229.87)
		)
		(stroke
			(width 0)
			(type default)
		)
	)
	(wire
		(pts
			(xy 264.16 232.41) (xy 270.51 232.41)
		)
		(stroke
			(width 0)
			(type default)
		)
	)
	(wire
		(pts
			(xy 358.14 132.08) (xy 363.22 132.08)
		)
		(stroke
			(width 0)
			(type default)
		)
	)
	(wire
		(pts
			(xy 81.28 224.79) (xy 81.28 238.76)
		)
		(stroke
			(width 0)
			(type default)
		)
	)
	(wire
		(pts
			(xy 326.39 55.88) (xy 327.66 55.88)
		)
		(stroke
			(width 0)
			(type default)
		)
	)
	(wire
		(pts
			(xy 67.31 254) (xy 72.39 254)
		)
		(stroke
			(width 0)
			(type default)
		)
	)
	(wire
		(pts
			(xy 50.8 224.79) (xy 62.23 224.79)
		)
		(stroke
			(width 0)
			(type default)
		)
	)
	(wire
		(pts
			(xy 349.25 67.31) (xy 349.25 55.88)
		)
		(stroke
			(width 0)
			(type default)
		)
	)
	(wire
		(pts
			(xy 133.35 114.3) (xy 127 114.3)
		)
		(stroke
			(width 0)
			(type default)
		)
	)
	(wire
		(pts
			(xy 222.25 232.41) (xy 229.87 232.41)
		)
		(stroke
			(width 0)
			(type default)
		)
	)
	(wire
		(pts
			(xy 363.22 130.81) (xy 363.22 132.08)
		)
		(stroke
			(width 0)
			(type default)
		)
	)
	(wire
		(pts
			(xy 237.49 237.49) (xy 237.49 232.41)
		)
		(stroke
			(width 0)
			(type default)
		)
	)
	(wire
		(pts
			(xy 262.89 142.24) (xy 262.89 144.78)
		)
		(stroke
			(width 0)
			(type default)
		)
	)
	(wire
		(pts
			(xy 67.31 254) (xy 63.5 254)
		)
		(stroke
			(width 0)
			(type default)
		)
	)
	(wire
		(pts
			(xy 88.9 210.82) (xy 82.55 210.82)
		)
		(stroke
			(width 0)
			(type default)
		)
	)
	(wire
		(pts
			(xy 189.23 220.98) (xy 204.47 220.98)
		)
		(stroke
			(width 0)
			(type default)
		)
	)
	(wire
		(pts
			(xy 81.28 60.96) (xy 81.28 62.23)
		)
		(stroke
			(width 0)
			(type default)
		)
	)
	(wire
		(pts
			(xy 127 97.79) (xy 133.35 97.79)
		)
		(stroke
			(width 0)
			(type default)
		)
	)
	(wire
		(pts
			(xy 97.79 97.79) (xy 97.79 88.9)
		)
		(stroke
			(width 0)
			(type default)
		)
	)
	(wire
		(pts
			(xy 327.66 142.24) (xy 327.66 144.78)
		)
		(stroke
			(width 0)
			(type default)
		)
	)
	(wire
		(pts
			(xy 217.17 242.57) (xy 217.17 245.11)
		)
		(stroke
			(width 0)
			(type default)
		)
	)
	(wire
		(pts
			(xy 363.22 54.61) (xy 363.22 55.88)
		)
		(stroke
			(width 0)
			(type default)
		)
	)
	(wire
		(pts
			(xy 129.54 223.52) (xy 129.54 224.79)
		)
		(stroke
			(width 0)
			(type default)
		)
	)
	(wire
		(pts
			(xy 189.23 229.87) (xy 189.23 220.98)
		)
		(stroke
			(width 0)
			(type default)
		)
	)
	(wire
		(pts
			(xy 388.62 134.62) (xy 388.62 137.16)
		)
		(stroke
			(width 0)
			(type default)
		)
	)
	(wire
		(pts
			(xy 81.28 149.86) (xy 81.28 148.59)
		)
		(stroke
			(width 0)
			(type default)
		)
	)
	(wire
		(pts
			(xy 31.75 224.79) (xy 31.75 231.14)
		)
		(stroke
			(width 0)
			(type default)
		)
	)
	(wire
		(pts
			(xy 375.92 222.25) (xy 375.92 223.52)
		)
		(stroke
			(width 0)
			(type default)
		)
	)
	(wire
		(pts
			(xy 347.98 222.25) (xy 359.41 222.25)
		)
		(stroke
			(width 0)
			(type default)
		)
	)
	(wire
		(pts
			(xy 279.4 50.8) (xy 279.4 60.96)
		)
		(stroke
			(width 0)
			(type default)
		)
	)
	(wire
		(pts
			(xy 308.61 66.04) (xy 327.66 66.04)
		)
		(stroke
			(width 0)
			(type default)
		)
	)
	(wire
		(pts
			(xy 115.57 124.46) (xy 115.57 114.3)
		)
		(stroke
			(width 0)
			(type default)
		)
	)
	(wire
		(pts
			(xy 115.57 72.39) (xy 115.57 62.23)
		)
		(stroke
			(width 0)
			(type default)
		)
	)
	(wire
		(pts
			(xy 198.12 237.49) (xy 199.39 237.49)
		)
		(stroke
			(width 0)
			(type default)
		)
	)
	(wire
		(pts
			(xy 81.28 139.7) (xy 81.28 140.97)
		)
		(stroke
			(width 0)
			(type default)
		)
	)
	(wire
		(pts
			(xy 320.04 55.88) (xy 321.31 55.88)
		)
		(stroke
			(width 0)
			(type default)
		)
	)
	(wire
		(pts
			(xy 63.5 254) (xy 63.5 256.54)
		)
		(stroke
			(width 0)
			(type default)
		)
	)
	(wire
		(pts
			(xy 199.39 234.95) (xy 196.85 234.95)
		)
		(stroke
			(width 0)
			(type default)
		)
	)
	(wire
		(pts
			(xy 262.89 59.69) (xy 262.89 55.88)
		)
		(stroke
			(width 0)
			(type default)
		)
	)
	(wire
		(pts
			(xy 97.79 62.23) (xy 104.14 62.23)
		)
		(stroke
			(width 0)
			(type default)
		)
	)
	(wire
		(pts
			(xy 250.19 231.14) (xy 250.19 232.41)
		)
		(stroke
			(width 0)
			(type default)
		)
	)
	(wire
		(pts
			(xy 334.01 218.44) (xy 334.01 217.17)
		)
		(stroke
			(width 0)
			(type default)
		)
	)
	(wire
		(pts
			(xy 102.87 241.3) (xy 102.87 243.84)
		)
		(stroke
			(width 0)
			(type default)
		)
	)
	(wire
		(pts
			(xy 110.49 224.79) (xy 119.38 224.79)
		)
		(stroke
			(width 0)
			(type default)
		)
	)
	(polyline
		(pts
			(xy 300.99 168.91) (xy 300.99 254)
		)
		(stroke
			(width 0)
			(type dash)
		)
	)
	(wire
		(pts
			(xy 346.71 219.71) (xy 346.71 214.63)
		)
		(stroke
			(width 0)
			(type default)
		)
	)
	(wire
		(pts
			(xy 279.4 121.92) (xy 279.4 123.19)
		)
		(stroke
			(width 0)
			(type default)
		)
	)
	(wire
		(pts
			(xy 388.62 60.96) (xy 388.62 63.5)
		)
		(stroke
			(width 0)
			(type default)
		)
	)
	(wire
		(pts
			(xy 168.91 229.87) (xy 168.91 236.22)
		)
		(stroke
			(width 0)
			(type default)
		)
	)
	(wire
		(pts
			(xy 88.9 118.11) (xy 88.9 114.3)
		)
		(stroke
			(width 0)
			(type default)
		)
	)
	(wire
		(pts
			(xy 31.75 243.84) (xy 31.75 245.11)
		)
		(stroke
			(width 0)
			(type default)
		)
	)
	(wire
		(pts
			(xy 31.75 224.79) (xy 50.8 224.79)
		)
		(stroke
			(width 0)
			(type default)
		)
	)
	(wire
		(pts
			(xy 76.2 223.52) (xy 76.2 224.79)
		)
		(stroke
			(width 0)
			(type default)
		)
	)
	(wire
		(pts
			(xy 309.88 223.52) (xy 326.39 223.52)
		)
		(stroke
			(width 0)
			(type default)
		)
	)
	(wire
		(pts
			(xy 337.82 130.81) (xy 337.82 132.08)
		)
		(stroke
			(width 0)
			(type default)
		)
	)
	(wire
		(pts
			(xy 250.19 232.41) (xy 255.27 232.41)
		)
		(stroke
			(width 0)
			(type default)
		)
	)
	(wire
		(pts
			(xy 309.88 223.52) (xy 309.88 224.79)
		)
		(stroke
			(width 0)
			(type default)
		)
	)
	(wire
		(pts
			(xy 168.91 248.92) (xy 168.91 250.19)
		)
		(stroke
			(width 0)
			(type default)
		)
	)
	(wire
		(pts
			(xy 104.14 124.46) (xy 97.79 124.46)
		)
		(stroke
			(width 0)
			(type default)
		)
	)
	(wire
		(pts
			(xy 109.22 72.39) (xy 115.57 72.39)
		)
		(stroke
			(width 0)
			(type default)
		)
	)
	(wire
		(pts
			(xy 133.35 62.23) (xy 127 62.23)
		)
		(stroke
			(width 0)
			(type default)
		)
	)
	(wire
		(pts
			(xy 67.31 223.52) (xy 67.31 224.79)
		)
		(stroke
			(width 0)
			(type default)
		)
	)
	(wire
		(pts
			(xy 100.33 210.82) (xy 100.33 224.79)
		)
		(stroke
			(width 0)
			(type default)
		)
	)
	(wire
		(pts
			(xy 97.79 149.86) (xy 97.79 140.97)
		)
		(stroke
			(width 0)
			(type default)
		)
	)
	(wire
		(pts
			(xy 234.95 232.41) (xy 237.49 232.41)
		)
		(stroke
			(width 0)
			(type default)
		)
	)
	(wire
		(pts
			(xy 119.38 224.79) (xy 129.54 224.79)
		)
		(stroke
			(width 0)
			(type default)
		)
	)
	(wire
		(pts
			(xy 115.57 140.97) (xy 121.92 140.97)
		)
		(stroke
			(width 0)
			(type default)
		)
	)
	(wire
		(pts
			(xy 374.65 222.25) (xy 375.92 222.25)
		)
		(stroke
			(width 0)
			(type default)
		)
	)
	(wire
		(pts
			(xy 81.28 114.3) (xy 88.9 114.3)
		)
		(stroke
			(width 0)
			(type default)
		)
	)
	(wire
		(pts
			(xy 115.57 62.23) (xy 109.22 62.23)
		)
		(stroke
			(width 0)
			(type default)
		)
	)
	(wire
		(pts
			(xy 327.66 138.43) (xy 327.66 142.24)
		)
		(stroke
			(width 0)
			(type default)
		)
	)
	(wire
		(pts
			(xy 88.9 140.97) (xy 97.79 140.97)
		)
		(stroke
			(width 0)
			(type default)
		)
	)
	(wire
		(pts
			(xy 63.5 233.68) (xy 63.5 237.49)
		)
		(stroke
			(width 0)
			(type default)
		)
	)
	(wire
		(pts
			(xy 93.98 210.82) (xy 100.33 210.82)
		)
		(stroke
			(width 0)
			(type default)
		)
	)
	(wire
		(pts
			(xy 168.91 114.3) (xy 162.56 114.3)
		)
		(stroke
			(width 0)
			(type default)
		)
	)
	(wire
		(pts
			(xy 185.42 229.87) (xy 189.23 229.87)
		)
		(stroke
			(width 0)
			(type default)
		)
	)
	(wire
		(pts
			(xy 340.36 223.52) (xy 340.36 224.79)
		)
		(stroke
			(width 0)
			(type default)
		)
	)
	(wire
		(pts
			(xy 133.35 140.97) (xy 127 140.97)
		)
		(stroke
			(width 0)
			(type default)
		)
	)
	(wire
		(pts
			(xy 320.04 60.96) (xy 320.04 55.88)
		)
		(stroke
			(width 0)
			(type default)
		)
	)
	(wire
		(pts
			(xy 180.34 236.22) (xy 180.34 237.49)
		)
		(stroke
			(width 0)
			(type default)
		)
	)
	(wire
		(pts
			(xy 104.14 72.39) (xy 97.79 72.39)
		)
		(stroke
			(width 0)
			(type default)
		)
	)
	(wire
		(pts
			(xy 363.22 55.88) (xy 369.57 55.88)
		)
		(stroke
			(width 0)
			(type default)
		)
	)
	(wire
		(pts
			(xy 330.2 217.17) (xy 334.01 217.17)
		)
		(stroke
			(width 0)
			(type default)
		)
	)
	(wire
		(pts
			(xy 327.66 62.23) (xy 327.66 66.04)
		)
		(stroke
			(width 0)
			(type default)
		)
	)
	(wire
		(pts
			(xy 133.35 72.39) (xy 133.35 62.23)
		)
		(stroke
			(width 0)
			(type default)
		)
	)
	(wire
		(pts
			(xy 375.92 153.67) (xy 375.92 152.4)
		)
		(stroke
			(width 0)
			(type default)
		)
	)
	(label "FB_1V8"
		(at 309.88 66.04 0)
		(effects
			(font
				(size 1.27 1.27)
			)
			(justify left bottom)
		)
	)
	(label "FB_1V2"
		(at 309.88 142.24 0)
		(effects
			(font
				(size 1.27 1.27)
			)
			(justify left bottom)
		)
	)
	(label "EN_1V2"
		(at 280.67 137.16 0)
		(effects
			(font
				(size 1.27 1.27)
			)
			(justify left bottom)
		)
	)
	(label "FFC_5V_EN"
		(at 347.98 222.25 0)
		(effects
			(font
				(size 1.27 1.27)
			)
			(justify left bottom)
		)
	)
	(label "OUT_1V8"
		(at 367.03 71.12 0)
		(effects
			(font
				(size 1.27 1.27)
			)
			(justify left bottom)
		)
	)
	(label "FFC_5V_ISET"
		(at 374.65 219.71 0)
		(effects
			(font
				(size 1.27 1.27)
			)
			(justify left bottom)
		)
	)
	(label "SW_1V8"
		(at 309.88 55.88 0)
		(effects
			(font
				(size 1.27 1.27)
			)
			(justify left bottom)
		)
	)
	(label "EN_12V"
		(at 189.23 238.76 0)
		(effects
			(font
				(size 1.27 1.27)
			)
			(justify left bottom)
		)
	)
	(label "OUT_12V"
		(at 238.76 232.41 0)
		(effects
			(font
				(size 1.27 1.27)
			)
			(justify left bottom)
		)
	)
	(label "OUT_12V"
		(at 275.59 240.03 270)
		(effects
			(font
				(size 1.27 1.27)
			)
			(justify right bottom)
		)
	)
	(label "OUT_1V2"
		(at 367.03 152.4 0)
		(effects
			(font
				(size 1.27 1.27)
			)
			(justify left bottom)
		)
	)
	(label "EN_1V8"
		(at 280.67 60.96 0)
		(effects
			(font
				(size 1.27 1.27)
			)
			(justify left bottom)
		)
	)
	(label "FFC_5V_EN"
		(at 326.39 223.52 180)
		(effects
			(font
				(size 1.27 1.27)
			)
			(justify right bottom)
		)
	)
	(label "OUT_1V8"
		(at 340.36 55.88 0)
		(effects
			(font
				(size 1.27 1.27)
			)
			(justify left bottom)
		)
	)
	(label "SW_12V"
		(at 214.63 232.41 0)
		(effects
			(font
				(size 1.27 1.27)
			)
			(justify left bottom)
		)
	)
	(label "FB_12V"
		(at 214.63 237.49 0)
		(effects
			(font
				(size 1.27 1.27)
			)
			(justify left bottom)
		)
	)
	(label "OUT_1V2"
		(at 340.36 132.08 0)
		(effects
			(font
				(size 1.27 1.27)
			)
			(justify left bottom)
		)
	)
	(label "FFC_5V_EN"
		(at 53.34 233.68 0)
		(effects
			(font
				(size 1.27 1.27)
			)
			(justify left bottom)
		)
	)
	(label "SW_1V2"
		(at 309.88 132.08 0)
		(effects
			(font
				(size 1.27 1.27)
			)
			(justify left bottom)
		)
	)
	(label "FFC_5V_FLG"
		(at 347.98 219.71 0)
		(effects
			(font
				(size 1.27 1.27)
			)
			(justify left bottom)
		)
	)
	(hierarchical_label "FFC_5V"
		(shape input)
		(at 330.2 217.17 180)
		(effects
			(font
				(size 1.27 1.27)
			)
			(justify right)
		)
	)
	(hierarchical_label "PoCA"
		(shape output)
		(at 168.91 62.23 0)
		(effects
			(font
				(size 1.27 1.27)
			)
			(justify left)
		)
	)
	(hierarchical_label "FFC_5V"
		(shape input)
		(at 309.88 215.9 90)
		(effects
			(font
				(size 1.27 1.27)
			)
			(justify left)
		)
	)
	(hierarchical_label "DC_IN"
		(shape input)
		(at 30.48 224.79 180)
		(effects
			(font
				(size 1.27 1.27)
			)
			(justify right)
		)
	)
	(hierarchical_label "PoCD"
		(shape output)
		(at 168.91 140.97 0)
		(effects
			(font
				(size 1.27 1.27)
			)
			(justify left)
		)
	)
	(hierarchical_label "PoCB"
		(shape output)
		(at 168.91 88.9 0)
		(effects
			(font
				(size 1.27 1.27)
			)
			(justify left)
		)
	)
	(hierarchical_label "PoCC"
		(shape output)
		(at 168.91 114.3 0)
		(effects
			(font
				(size 1.27 1.27)
			)
			(justify left)
		)
	)
	(symbol
		(lib_id "antmicropower:GND")
		(at 279.4 67.31 0)
		(unit 1)
		(exclude_from_sim no)
		(in_bom yes)
		(on_board yes)
		(dnp no)
		(property "Reference" "#PWR0113"
			(at 288.29 69.85 0)
			(effects
				(font
					(size 1.27 1.27)
					(thickness 0.15)
				)
				(justify left bottom)
				(hide yes)
			)
		)
		(property "Value" "GND"
			(at 279.4 71.12 0)
			(effects
				(font
					(size 1.27 1.27)
					(thickness 0.15)
				)
			)
		)
		(property "Footprint" ""
			(at 288.29 74.93 0)
			(effects
				(font
					(size 1.27 1.27)
					(thickness 0.15)
				)
				(justify left bottom)
				(hide yes)
			)
		)
		(property "Datasheet" ""
			(at 288.29 80.01 0)
			(effects
				(font
					(size 1.27 1.27)
					(thickness 0.15)
				)
				(justify left bottom)
				(hide yes)
			)
		)
		(property "Description" ""
			(at 279.4 67.31 0)
			(effects
				(font
					(size 1.27 1.27)
				)
				(hide yes)
			)
		)
		(property "Author" "Antmicro"
			(at 288.29 74.93 0)
			(effects
				(font
					(size 1.27 1.27)
					(thickness 0.15)
				)
				(justify left bottom)
				(hide yes)
			)
		)
		(property "License" "Apache-2.0"
			(at 288.29 77.47 0)
			(effects
				(font
					(size 1.27 1.27)
					(thickness 0.15)
				)
				(justify left bottom)
				(hide yes)
			)
		)
		(pin "1"
		)
		(instances
			(project "gmsl-deserializer"
				(path ""
					(reference "#PWR0113")
					(unit 1)
				)
			)
		)
	)
	(symbol
		(lib_id "antmicroResistors0402:R_470R_0402")
		(at 388.62 53.34 90)
		(unit 1)
		(exclude_from_sim no)
		(in_bom yes)
		(on_board yes)
		(dnp no)
		(fields_autoplaced yes)
		(property "Reference" "R81"
			(at 391.16 49.5299 90)
			(effects
				(font
					(size 1.27 1.27)
					(thickness 0.15)
				)
				(justify right)
			)
		)
		(property "Value" "R_470R_0402"
			(at 401.32 33.02 0)
			(effects
				(font
					(size 1.27 1.27)
					(thickness 0.15)
				)
				(justify left bottom)
				(hide yes)
			)
		)
		(property "Footprint" "antmicro-footprints:R_0402_1005Metric"
			(at 403.86 33.02 0)
			(effects
				(font
					(size 1.27 1.27)
					(thickness 0.15)
				)
				(justify left bottom)
				(hide yes)
			)
		)
		(property "Datasheet" "https://www.bourns.com/docs/product-datasheets/cr.pdf"
			(at 406.4 33.02 0)
			(effects
				(font
					(size 1.27 1.27)
					(thickness 0.15)
				)
				(justify left bottom)
				(hide yes)
			)
		)
		(property "Description" "SMD Chip Resistor, 470 ohm, ± 1%, 62.5 mW, 0402 [1005 Metric], Thick Film, General Purpose"
			(at 388.62 53.34 0)
			(effects
				(font
					(size 1.27 1.27)
				)
				(hide yes)
			)
		)
		(property "MPN" "CR0402-FX-4700GLF"
			(at 408.94 33.02 0)
			(effects
				(font
					(size 1.27 1.27)
					(thickness 0.15)
				)
				(justify left bottom)
				(hide yes)
			)
		)
		(property "Manufacturer" "Bourns"
			(at 411.48 33.02 0)
			(effects
				(font
					(size 1.27 1.27)
					(thickness 0.15)
				)
				(justify left bottom)
				(hide yes)
			)
		)
		(property "License" "Apache-2.0"
			(at 414.02 33.02 0)
			(effects
				(font
					(size 1.27 1.27)
					(thickness 0.15)
				)
				(justify left bottom)
				(hide yes)
			)
		)
		(property "Author" "Antmicro"
			(at 416.56 33.02 0)
			(effects
				(font
					(size 1.27 1.27)
					(thickness 0.15)
				)
				(justify left bottom)
				(hide yes)
			)
		)
		(property "Val" "470R"
			(at 391.16 52.0699 90)
			(effects
				(font
					(size 1.27 1.27)
					(thickness 0.15)
				)
				(justify right)
			)
		)
		(property "Tolerance" "1%"
			(at 398.78 33.02 0)
			(effects
				(font
					(size 1.27 1.27)
				)
				(justify left bottom)
				(hide yes)
			)
		)
		(pin "1"
		)
		(pin "2"
		)
		(instances
			(project "gmsl-deserializer"
				(path ""
					(reference "R81")
					(unit 1)
				)
			)
		)
	)
	(symbol
		(lib_id "antmicroTestPoints:TP_0.75mm_SMD")
		(at 72.39 252.73 90)
		(unit 1)
		(exclude_from_sim no)
		(in_bom yes)
		(on_board yes)
		(dnp no)
		(property "Reference" "TP26"
			(at 71.12 247.65 90)
			(effects
				(font
					(size 1.27 1.27)
					(thickness 0.15)
				)
				(justify right)
			)
		)
		(property "Value" "TP_0.75mm_SMD"
			(at 76.2 241.935 0)
			(effects
				(font
					(size 1.27 1.27)
					(thickness 0.15)
				)
				(justify left bottom)
				(hide yes)
			)
		)
		(property "Footprint" "antmicro-footprints:TP_SMD_0.75mm"
			(at 78.74 241.935 0)
			(effects
				(font
					(size 1.27 1.27)
					(thickness 0.15)
				)
				(justify left bottom)
				(hide yes)
			)
		)
		(property "Datasheet" ""
			(at 85.09 234.95 0)
			(effects
				(font
					(size 1.27 1.27)
					(thickness 0.15)
				)
				(justify left bottom)
				(hide yes)
			)
		)
		(property "Description" "SMT test point"
			(at 72.39 252.73 0)
			(effects
				(font
					(size 1.27 1.27)
				)
				(hide yes)
			)
		)
		(property "MPN" ""
			(at 83.82 241.935 0)
			(effects
				(font
					(size 1.27 1.27)
					(thickness 0.15)
				)
				(justify left bottom)
				(hide yes)
			)
		)
		(property "Manufacturer" ""
			(at 78.74 241.935 0)
			(effects
				(font
					(size 1.27 1.27)
					(thickness 0.15)
				)
				(justify left bottom)
				(hide yes)
			)
		)
		(property "Author" "Antmicro"
			(at 81.28 241.935 0)
			(effects
				(font
					(size 1.27 1.27)
					(thickness 0.15)
				)
				(justify left bottom)
				(hide yes)
			)
		)
		(property "License" "Apache-2.0"
			(at 83.82 241.935 0)
			(effects
				(font
					(size 1.27 1.27)
					(thickness 0.15)
				)
				(justify left bottom)
				(hide yes)
			)
		)
		(pin "1"
		)
		(instances
			(project "gmsl-deserializer"
				(path ""
					(reference "TP26")
					(unit 1)
				)
			)
		)
	)
	(symbol
		(lib_id "antmicroResistors0402:R_0R_0402")
		(at 189.23 236.22 90)
		(unit 1)
		(exclude_from_sim no)
		(in_bom yes)
		(on_board yes)
		(dnp no)
		(property "Reference" "R28"
			(at 191.135 232.4099 90)
			(effects
				(font
					(size 1.27 1.27)
					(thickness 0.15)
				)
				(justify right)
			)
		)
		(property "Value" "R_0R_0402"
			(at 201.93 215.9 0)
			(effects
				(font
					(size 1.27 1.27)
					(thickness 0.15)
				)
				(justify left bottom)
				(hide yes)
			)
		)
		(property "Footprint" "antmicro-footprints:R_0402_1005Metric"
			(at 204.47 215.9 0)
			(effects
				(font
					(size 1.27 1.27)
					(thickness 0.15)
				)
				(justify left bottom)
				(hide yes)
			)
		)
		(property "Datasheet" "https://industrial.panasonic.com/cdbs/www-data/pdf/RDA0000/AOA0000C301.pdf"
			(at 207.01 215.9 0)
			(effects
				(font
					(size 1.27 1.27)
					(thickness 0.15)
				)
				(justify left bottom)
				(hide yes)
			)
		)
		(property "Description" "SMD Chip Resistor, Jumper, 0 ohm, 100 mW, 0402 [1005 Metric], Thick Film, General Purpose"
			(at 189.23 236.22 0)
			(effects
				(font
					(size 1.27 1.27)
				)
				(hide yes)
			)
		)
		(property "MPN" "ERJ2GE0R00X"
			(at 209.55 215.9 0)
			(effects
				(font
					(size 1.27 1.27)
					(thickness 0.15)
				)
				(justify left bottom)
				(hide yes)
			)
		)
		(property "Manufacturer" "Panasonic"
			(at 212.09 215.9 0)
			(effects
				(font
					(size 1.27 1.27)
					(thickness 0.15)
				)
				(justify left bottom)
				(hide yes)
			)
		)
		(property "License" "Apache-2.0"
			(at 214.63 215.9 0)
			(effects
				(font
					(size 1.27 1.27)
					(thickness 0.15)
				)
				(justify left bottom)
				(hide yes)
			)
		)
		(property "Author" "Antmicro"
			(at 217.17 215.9 0)
			(effects
				(font
					(size 1.27 1.27)
					(thickness 0.15)
				)
				(justify left bottom)
				(hide yes)
			)
		)
		(property "Val" "0R"
			(at 191.135 234.9499 90)
			(effects
				(font
					(size 1.27 1.27)
					(thickness 0.15)
				)
				(justify right)
			)
		)
		(property "Tolerance" "~"
			(at 199.39 215.9 0)
			(effects
				(font
					(size 1.27 1.27)
				)
				(justify left bottom)
				(hide yes)
			)
		)
		(property "Current" "1A"
			(at 219.71 215.9 0)
			(effects
				(font
					(size 1.27 1.27)
					(thickness 0.15)
				)
				(justify left bottom)
				(hide yes)
			)
		)
		(pin "1"
		)
		(pin "2"
		)
		(instances
			(project "gmsl-deserializer"
				(path ""
					(reference "R28")
					(unit 1)
				)
			)
		)
	)
	(symbol
		(lib_id "antmicroFixedInductors:L_6u8_1A_Coilcraft-1210POC")
		(at 121.92 140.97 0)
		(unit 1)
		(exclude_from_sim no)
		(in_bom yes)
		(on_board yes)
		(dnp no)
		(property "Reference" "L8"
			(at 124.46 135.89 0)
			(effects
				(font
					(size 1.27 1.27)
					(thickness 0.15)
				)
			)
		)
		(property "Value" "L_6u8_1A_Coilcraft-1210POC"
			(at 135.89 143.51 0)
			(effects
				(font
					(size 1.27 1.27)
					(thickness 0.15)
				)
				(justify left bottom)
				(hide yes)
			)
		)
		(property "Footprint" "antmicro-footprints:L_Coilcraft-1210POC"
			(at 135.89 148.59 0)
			(effects
				(font
					(size 1.27 1.27)
					(thickness 0.15)
				)
				(justify left bottom)
				(hide yes)
			)
		)
		(property "Datasheet" "https://www.coilcraft.com/getmedia/5e8de018-68c5-4442-84ce-d5212c44660c/1210poc.pdf"
			(at 135.89 151.13 0)
			(effects
				(font
					(size 1.27 1.27)
					(thickness 0.15)
				)
				(justify left bottom)
				(hide yes)
			)
		)
		(property "Description" "Power Inductor (SMT), 6.8 µH, 9.2 A, Shielded, 12.8 A, XAL7070"
			(at 121.92 140.97 0)
			(effects
				(font
					(size 1.27 1.27)
				)
				(hide yes)
			)
		)
		(property "Val" "6u8/1A"
			(at 124.46 138.43 0)
			(effects
				(font
					(size 1.27 1.27)
					(thickness 0.15)
				)
			)
		)
		(property "Manufacturer" "Coilcraft"
			(at 135.89 153.67 0)
			(effects
				(font
					(size 1.27 1.27)
					(thickness 0.15)
				)
				(justify left bottom)
				(hide yes)
			)
		)
		(property "MPN" "1210POC-682"
			(at 135.89 156.21 0)
			(effects
				(font
					(size 1.27 1.27)
					(thickness 0.15)
				)
				(justify left bottom)
				(hide yes)
			)
		)
		(property "ISat" "1 A"
			(at 135.89 157.48 0)
			(effects
				(font
					(size 1.27 1.27)
				)
				(justify left)
				(hide yes)
			)
		)
		(property "IMax" "1.36 A"
			(at 135.89 161.29 0)
			(effects
				(font
					(size 1.27 1.27)
					(thickness 0.15)
				)
				(justify left bottom)
				(hide yes)
			)
		)
		(property "Size" "2.67x3.3"
			(at 135.89 163.83 0)
			(effects
				(font
					(size 1.27 1.27)
					(thickness 0.15)
				)
				(justify left bottom)
				(hide yes)
			)
		)
		(property "Author" "Antmicro"
			(at 135.89 166.37 0)
			(effects
				(font
					(size 1.27 1.27)
					(thickness 0.15)
				)
				(justify left bottom)
				(hide yes)
			)
		)
		(property "License" "Apache-2.0"
			(at 135.89 168.91 0)
			(effects
				(font
					(size 1.27 1.27)
					(thickness 0.15)
				)
				(justify left bottom)
				(hide yes)
			)
		)
		(pin "1"
		)
		(pin "2"
		)
		(instances
			(project "gmsl-deserializer"
				(path ""
					(reference "L8")
					(unit 1)
				)
			)
		)
	)
	(symbol
		(lib_id "antmicroFixedInductors:L_22u_1.12A_Coilcraft-MSS6132T")
		(at 104.14 88.9 0)
		(unit 1)
		(exclude_from_sim no)
		(in_bom yes)
		(on_board yes)
		(dnp no)
		(fields_autoplaced yes)
		(property "Reference" "L2"
			(at 106.68 83.82 0)
			(effects
				(font
					(size 1.27 1.27)
					(thickness 0.15)
				)
			)
		)
		(property "Value" "L_22u_1.12A_Coilcraft-MSS6132T"
			(at 118.11 91.44 0)
			(effects
				(font
					(size 1.27 1.27)
					(thickness 0.15)
				)
				(justify left bottom)
				(hide yes)
			)
		)
		(property "Footprint" "antmicro-footprints:L_Coilcraft-MSS6132T"
			(at 118.11 96.52 0)
			(effects
				(font
					(size 1.27 1.27)
					(thickness 0.15)
				)
				(justify left bottom)
				(hide yes)
			)
		)
		(property "Datasheet" "https://www.coilcraft.com/getmedia/d035c9b3-191d-46aa-ab3f-5c1a849157c1/mss6132t.pdf"
			(at 118.11 99.06 0)
			(effects
				(font
					(size 1.27 1.27)
					(thickness 0.15)
				)
				(justify left bottom)
				(hide yes)
			)
		)
		(property "Description" "Power Inductor (SMT), 22 µH, 1.85 A, Shielded, 2.45 A, WE-MAPI"
			(at 104.14 88.9 0)
			(effects
				(font
					(size 1.27 1.27)
				)
				(hide yes)
			)
		)
		(property "Val" "22u/1.12A"
			(at 106.68 86.36 0)
			(effects
				(font
					(size 1.27 1.27)
					(thickness 0.15)
				)
			)
		)
		(property "Manufacturer" "Coilcraft"
			(at 118.11 101.6 0)
			(effects
				(font
					(size 1.27 1.27)
					(thickness 0.15)
				)
				(justify left bottom)
				(hide yes)
			)
		)
		(property "MPN" "MSS6132T-223"
			(at 118.11 104.14 0)
			(effects
				(font
					(size 1.27 1.27)
					(thickness 0.15)
				)
				(justify left bottom)
				(hide yes)
			)
		)
		(property "ISat" "1.12A"
			(at 118.11 105.41 0)
			(effects
				(font
					(size 1.27 1.27)
				)
				(justify left)
				(hide yes)
			)
		)
		(property "IMax" "1.45A"
			(at 118.11 109.22 0)
			(effects
				(font
					(size 1.27 1.27)
					(thickness 0.15)
				)
				(justify left bottom)
				(hide yes)
			)
		)
		(property "Size" "6.1x6.1"
			(at 118.11 111.76 0)
			(effects
				(font
					(size 1.27 1.27)
					(thickness 0.15)
				)
				(justify left bottom)
				(hide yes)
			)
		)
		(property "Author" "Antmicro"
			(at 118.11 114.3 0)
			(effects
				(font
					(size 1.27 1.27)
					(thickness 0.15)
				)
				(justify left bottom)
				(hide yes)
			)
		)
		(property "License" "Apache-2.0"
			(at 118.11 116.84 0)
			(effects
				(font
					(size 1.27 1.27)
					(thickness 0.15)
				)
				(justify left bottom)
				(hide yes)
			)
		)
		(pin "1"
		)
		(pin "2"
		)
		(instances
			(project "gmsl-deserializer"
				(path ""
					(reference "L2")
					(unit 1)
				)
			)
		)
	)
	(symbol
		(lib_id "antmicropower:+1V8")
		(at 375.92 54.61 0)
		(unit 1)
		(exclude_from_sim no)
		(in_bom yes)
		(on_board yes)
		(dnp no)
		(property "Reference" "#PWR0118"
			(at 391.16 57.15 0)
			(effects
				(font
					(size 1.27 1.27)
					(thickness 0.15)
				)
				(justify left bottom)
				(hide yes)
			)
		)
		(property "Value" "+1V8"
			(at 375.92 50.8 0)
			(effects
				(font
					(size 1.27 1.27)
					(thickness 0.15)
				)
			)
		)
		(property "Footprint" ""
			(at 391.16 62.23 0)
			(effects
				(font
					(size 1.27 1.27)
					(thickness 0.15)
				)
				(justify left bottom)
				(hide yes)
			)
		)
		(property "Datasheet" ""
			(at 391.16 64.77 0)
			(effects
				(font
					(size 1.27 1.27)
					(thickness 0.15)
				)
				(justify left bottom)
				(hide yes)
			)
		)
		(property "Description" ""
			(at 375.92 54.61 0)
			(effects
				(font
					(size 1.27 1.27)
				)
				(hide yes)
			)
		)
		(property "Author" "Antmicro"
			(at 391.16 62.23 0)
			(effects
				(font
					(size 1.27 1.27)
					(thickness 0.15)
				)
				(justify left bottom)
				(hide yes)
			)
		)
		(property "License" "Apache-2.0"
			(at 391.16 64.77 0)
			(effects
				(font
					(size 1.27 1.27)
					(thickness 0.15)
				)
				(justify left bottom)
				(hide yes)
			)
		)
		(pin "1"
		)
		(instances
			(project "gmsl-deserializer"
				(path ""
					(reference "#PWR0118")
					(unit 1)
				)
			)
		)
	)
	(symbol
		(lib_id "antmicroFixedInductors:L_22u_1.12A_Coilcraft-MSS6132T")
		(at 104.14 114.3 0)
		(unit 1)
		(exclude_from_sim no)
		(in_bom yes)
		(on_board yes)
		(dnp no)
		(fields_autoplaced yes)
		(property "Reference" "L3"
			(at 106.68 109.22 0)
			(effects
				(font
					(size 1.27 1.27)
					(thickness 0.15)
				)
			)
		)
		(property "Value" "L_22u_1.12A_Coilcraft-MSS6132T"
			(at 118.11 116.84 0)
			(effects
				(font
					(size 1.27 1.27)
					(thickness 0.15)
				)
				(justify left bottom)
				(hide yes)
			)
		)
		(property "Footprint" "antmicro-footprints:L_Coilcraft-MSS6132T"
			(at 118.11 121.92 0)
			(effects
				(font
					(size 1.27 1.27)
					(thickness 0.15)
				)
				(justify left bottom)
				(hide yes)
			)
		)
		(property "Datasheet" "https://www.coilcraft.com/getmedia/d035c9b3-191d-46aa-ab3f-5c1a849157c1/mss6132t.pdf"
			(at 118.11 124.46 0)
			(effects
				(font
					(size 1.27 1.27)
					(thickness 0.15)
				)
				(justify left bottom)
				(hide yes)
			)
		)
		(property "Description" "Power Inductor (SMT), 22 µH, 1.85 A, Shielded, 2.45 A, WE-MAPI"
			(at 104.14 114.3 0)
			(effects
				(font
					(size 1.27 1.27)
				)
				(hide yes)
			)
		)
		(property "Val" "22u/1.12A"
			(at 106.68 111.76 0)
			(effects
				(font
					(size 1.27 1.27)
					(thickness 0.15)
				)
			)
		)
		(property "Manufacturer" "Coilcraft"
			(at 118.11 127 0)
			(effects
				(font
					(size 1.27 1.27)
					(thickness 0.15)
				)
				(justify left bottom)
				(hide yes)
			)
		)
		(property "MPN" "MSS6132T-223"
			(at 118.11 129.54 0)
			(effects
				(font
					(size 1.27 1.27)
					(thickness 0.15)
				)
				(justify left bottom)
				(hide yes)
			)
		)
		(property "ISat" "1.12A"
			(at 118.11 130.81 0)
			(effects
				(font
					(size 1.27 1.27)
				)
				(justify left)
				(hide yes)
			)
		)
		(property "IMax" "1.45A"
			(at 118.11 134.62 0)
			(effects
				(font
					(size 1.27 1.27)
					(thickness 0.15)
				)
				(justify left bottom)
				(hide yes)
			)
		)
		(property "Size" "6.1x6.1"
			(at 118.11 137.16 0)
			(effects
				(font
					(size 1.27 1.27)
					(thickness 0.15)
				)
				(justify left bottom)
				(hide yes)
			)
		)
		(property "Author" "Antmicro"
			(at 118.11 139.7 0)
			(effects
				(font
					(size 1.27 1.27)
					(thickness 0.15)
				)
				(justify left bottom)
				(hide yes)
			)
		)
		(property "License" "Apache-2.0"
			(at 118.11 142.24 0)
			(effects
				(font
					(size 1.27 1.27)
					(thickness 0.15)
				)
				(justify left bottom)
				(hide yes)
			)
		)
		(pin "1"
		)
		(pin "2"
		)
		(instances
			(project "gmsl-deserializer"
				(path ""
					(reference "L3")
					(unit 1)
				)
			)
		)
	)
	(symbol
		(lib_id "antmicroCapacitors0402:C_10n_0402")
		(at 88.9 96.52 90)
		(unit 1)
		(exclude_from_sim no)
		(in_bom yes)
		(on_board yes)
		(dnp no)
		(property "Reference" "C11"
			(at 89.535 92.075 90)
			(effects
				(font
					(size 1.27 1.27)
					(thickness 0.15)
				)
				(justify right)
			)
		)
		(property "Value" "C_10n_0402"
			(at 99.06 76.2 0)
			(effects
				(font
					(size 1.27 1.27)
					(thickness 0.15)
				)
				(justify left bottom)
				(hide yes)
			)
		)
		(property "Footprint" "antmicro-footprints:C_0402_1005Metric"
			(at 101.6 76.2 0)
			(effects
				(font
					(size 1.27 1.27)
					(thickness 0.15)
				)
				(justify left bottom)
				(hide yes)
			)
		)
		(property "Datasheet" "https://www.murata.com/products/productdetail?partno=GRM155R71H103KA88%23"
			(at 104.14 76.2 0)
			(effects
				(font
					(size 1.27 1.27)
					(thickness 0.15)
				)
				(justify left bottom)
				(hide yes)
			)
		)
		(property "Description" "SMD Multilayer Ceramic Capacitor, 10000 pF, 50 V, 0402 [1005 Metric], ± 10%, X7R, GRM Series"
			(at 88.9 96.52 0)
			(effects
				(font
					(size 1.27 1.27)
				)
				(hide yes)
			)
		)
		(property "MPN" "GRM155R71H103KA88D"
			(at 106.68 76.2 0)
			(effects
				(font
					(size 1.27 1.27)
					(thickness 0.15)
				)
				(justify left bottom)
				(hide yes)
			)
		)
		(property "Manufacturer" "Murata"
			(at 109.22 76.2 0)
			(effects
				(font
					(size 1.27 1.27)
					(thickness 0.15)
				)
				(justify left bottom)
				(hide yes)
			)
		)
		(property "License" "Apache-2.0"
			(at 111.76 76.2 0)
			(effects
				(font
					(size 1.27 1.27)
					(thickness 0.15)
				)
				(justify left bottom)
				(hide yes)
			)
		)
		(property "Author" "Antmicro"
			(at 114.3 76.2 0)
			(effects
				(font
					(size 1.27 1.27)
					(thickness 0.15)
				)
				(justify left bottom)
				(hide yes)
			)
		)
		(property "Val" "10n"
			(at 89.535 95.885 90)
			(effects
				(font
					(size 1.27 1.27)
					(thickness 0.15)
				)
				(justify right)
			)
		)
		(property "Voltage" "50V"
			(at 116.84 76.2 0)
			(effects
				(font
					(size 1.27 1.27)
				)
				(justify left bottom)
				(hide yes)
			)
		)
		(property "Dielectric" "X7R"
			(at 119.38 76.2 0)
			(effects
				(font
					(size 1.27 1.27)
				)
				(justify left bottom)
				(hide yes)
			)
		)
		(pin "1"
		)
		(pin "2"
		)
		(instances
			(project "gmsl-deserializer"
				(path ""
					(reference "C11")
					(unit 1)
				)
			)
		)
	)
	(symbol
		(lib_id "antmicroResistors0402:R_10k_0402")
		(at 279.4 50.8 90)
		(unit 1)
		(exclude_from_sim no)
		(in_bom yes)
		(on_board yes)
		(dnp no)
		(fields_autoplaced yes)
		(property "Reference" "R32"
			(at 281.305 46.9899 90)
			(effects
				(font
					(size 1.27 1.27)
					(thickness 0.15)
				)
				(justify right)
			)
		)
		(property "Value" "R_10k_0402"
			(at 292.1 30.48 0)
			(effects
				(font
					(size 1.27 1.27)
					(thickness 0.15)
				)
				(justify left bottom)
				(hide yes)
			)
		)
		(property "Footprint" "antmicro-footprints:R_0402_1005Metric"
			(at 294.64 30.48 0)
			(effects
				(font
					(size 1.27 1.27)
					(thickness 0.15)
				)
				(justify left bottom)
				(hide yes)
			)
		)
		(property "Datasheet" "https://www.bourns.com/docs/product-datasheets/cr.pdf"
			(at 297.18 30.48 0)
			(effects
				(font
					(size 1.27 1.27)
					(thickness 0.15)
				)
				(justify left bottom)
				(hide yes)
			)
		)
		(property "Description" "SMD Chip Resistor, 10 kohm, ± 1%, 62.5 mW, 0402 [1005 Metric], Thick Film, General Purpose"
			(at 279.4 50.8 0)
			(effects
				(font
					(size 1.27 1.27)
				)
				(hide yes)
			)
		)
		(property "MPN" "CR0402-FX-1002GLF"
			(at 299.72 30.48 0)
			(effects
				(font
					(size 1.27 1.27)
					(thickness 0.15)
				)
				(justify left bottom)
				(hide yes)
			)
		)
		(property "Manufacturer" "Bourns"
			(at 302.26 30.48 0)
			(effects
				(font
					(size 1.27 1.27)
					(thickness 0.15)
				)
				(justify left bottom)
				(hide yes)
			)
		)
		(property "License" "Apache-2.0"
			(at 304.8 30.48 0)
			(effects
				(font
					(size 1.27 1.27)
					(thickness 0.15)
				)
				(justify left bottom)
				(hide yes)
			)
		)
		(property "Author" "Antmicro"
			(at 307.34 30.48 0)
			(effects
				(font
					(size 1.27 1.27)
					(thickness 0.15)
				)
				(justify left bottom)
				(hide yes)
			)
		)
		(property "Val" "10k"
			(at 281.305 49.5299 90)
			(effects
				(font
					(size 1.27 1.27)
					(thickness 0.15)
				)
				(justify right)
			)
		)
		(property "Tolerance" "1%"
			(at 289.56 30.48 0)
			(effects
				(font
					(size 1.27 1.27)
				)
				(justify left bottom)
				(hide yes)
			)
		)
		(pin "1"
		)
		(pin "2"
		)
		(instances
			(project "gmsl-deserializer"
				(path ""
					(reference "R32")
					(unit 1)
				)
			)
		)
	)
	(symbol
		(lib_id "antmicroResistors0402:R_100k_0402")
		(at 375.92 77.47 90)
		(unit 1)
		(exclude_from_sim no)
		(in_bom yes)
		(on_board yes)
		(dnp no)
		(fields_autoplaced yes)
		(property "Reference" "R74"
			(at 378.46 73.6599 90)
			(effects
				(font
					(size 1.27 1.27)
					(thickness 0.15)
				)
				(justify right)
			)
		)
		(property "Value" "R_100k_0402"
			(at 388.62 57.15 0)
			(effects
				(font
					(size 1.27 1.27)
					(thickness 0.15)
				)
				(justify left bottom)
				(hide yes)
			)
		)
		(property "Footprint" "antmicro-footprints:R_0402_1005Metric"
			(at 391.16 57.15 0)
			(effects
				(font
					(size 1.27 1.27)
					(thickness 0.15)
				)
				(justify left bottom)
				(hide yes)
			)
		)
		(property "Datasheet" "https://www.bourns.com/docs/product-datasheets/cr.pdf"
			(at 393.7 57.15 0)
			(effects
				(font
					(size 1.27 1.27)
					(thickness 0.15)
				)
				(justify left bottom)
				(hide yes)
			)
		)
		(property "Description" "SMD Chip Resistor, 100 kohm, ± 1%, 62.5 mW, 0402 [1005 Metric], Thick Film, General Purpose"
			(at 375.92 77.47 0)
			(effects
				(font
					(size 1.27 1.27)
				)
				(hide yes)
			)
		)
		(property "MPN" "CR0402-FX-1003GLF"
			(at 396.24 57.15 0)
			(effects
				(font
					(size 1.27 1.27)
					(thickness 0.15)
				)
				(justify left bottom)
				(hide yes)
			)
		)
		(property "Manufacturer" "Bourns"
			(at 398.78 57.15 0)
			(effects
				(font
					(size 1.27 1.27)
					(thickness 0.15)
				)
				(justify left bottom)
				(hide yes)
			)
		)
		(property "License" "Apache-2.0"
			(at 401.32 57.15 0)
			(effects
				(font
					(size 1.27 1.27)
					(thickness 0.15)
				)
				(justify left bottom)
				(hide yes)
			)
		)
		(property "Author" "Antmicro"
			(at 403.86 57.15 0)
			(effects
				(font
					(size 1.27 1.27)
					(thickness 0.15)
				)
				(justify left bottom)
				(hide yes)
			)
		)
		(property "Val" "100k"
			(at 378.46 76.1999 90)
			(effects
				(font
					(size 1.27 1.27)
					(thickness 0.15)
				)
				(justify right)
			)
		)
		(property "Tolerance" "1%"
			(at 386.08 57.15 0)
			(effects
				(font
					(size 1.27 1.27)
				)
				(justify left bottom)
				(hide yes)
			)
		)
		(pin "1"
		)
		(pin "2"
		)
		(instances
			(project "gmsl-deserializer"
				(path ""
					(reference "R74")
					(unit 1)
				)
			)
		)
	)
	(symbol
		(lib_id "antmicroCapacitors0402:C_100n_0402")
		(at 81.28 148.59 90)
		(unit 1)
		(exclude_from_sim no)
		(in_bom yes)
		(on_board yes)
		(dnp no)
		(property "Reference" "C9"
			(at 81.915 144.145 90)
			(effects
				(font
					(size 1.27 1.27)
					(thickness 0.15)
				)
				(justify right)
			)
		)
		(property "Value" "C_100n_0402"
			(at 91.44 128.27 0)
			(effects
				(font
					(size 1.27 1.27)
					(thickness 0.15)
				)
				(justify left bottom)
				(hide yes)
			)
		)
		(property "Footprint" "antmicro-footprints:C_0402_1005Metric"
			(at 93.98 128.27 0)
			(effects
				(font
					(size 1.27 1.27)
					(thickness 0.15)
				)
				(justify left bottom)
				(hide yes)
			)
		)
		(property "Datasheet" "https://www.murata.com/products/productdetail?partno=GRM155R61H104KE14%23"
			(at 96.52 128.27 0)
			(effects
				(font
					(size 1.27 1.27)
					(thickness 0.15)
				)
				(justify left bottom)
				(hide yes)
			)
		)
		(property "Description" "SMD Multilayer Ceramic Capacitor, 0.1 µF, 50 V, 0402 [1005 Metric], ± 10%, X5R, GRM Series"
			(at 81.28 148.59 0)
			(effects
				(font
					(size 1.27 1.27)
				)
				(hide yes)
			)
		)
		(property "MPN" "GRM155R61H104KE14D"
			(at 99.06 128.27 0)
			(effects
				(font
					(size 1.27 1.27)
					(thickness 0.15)
				)
				(justify left bottom)
				(hide yes)
			)
		)
		(property "Manufacturer" "Murata"
			(at 101.6 128.27 0)
			(effects
				(font
					(size 1.27 1.27)
					(thickness 0.15)
				)
				(justify left bottom)
				(hide yes)
			)
		)
		(property "License" "Apache-2.0"
			(at 104.14 128.27 0)
			(effects
				(font
					(size 1.27 1.27)
					(thickness 0.15)
				)
				(justify left bottom)
				(hide yes)
			)
		)
		(property "Author" "Antmicro"
			(at 106.68 128.27 0)
			(effects
				(font
					(size 1.27 1.27)
					(thickness 0.15)
				)
				(justify left bottom)
				(hide yes)
			)
		)
		(property "Val" "100n"
			(at 81.915 147.955 90)
			(effects
				(font
					(size 1.27 1.27)
					(thickness 0.15)
				)
				(justify right)
			)
		)
		(property "Voltage" "50V"
			(at 109.22 128.27 0)
			(effects
				(font
					(size 1.27 1.27)
				)
				(justify left bottom)
				(hide yes)
			)
		)
		(property "Dielectric" "X5R"
			(at 111.76 128.27 0)
			(effects
				(font
					(size 1.27 1.27)
				)
				(justify left bottom)
				(hide yes)
			)
		)
		(pin "1"
		)
		(pin "2"
		)
		(instances
			(project "gmsl-deserializer"
				(path ""
					(reference "C9")
					(unit 1)
				)
			)
		)
	)
	(symbol
		(lib_id "antmicropower:GND")
		(at 340.36 224.79 0)
		(unit 1)
		(exclude_from_sim no)
		(in_bom yes)
		(on_board yes)
		(dnp no)
		(property "Reference" "#PWR056"
			(at 349.25 227.33 0)
			(effects
				(font
					(size 1.27 1.27)
					(thickness 0.15)
				)
				(justify left bottom)
				(hide yes)
			)
		)
		(property "Value" "GND"
			(at 340.36 228.6 0)
			(effects
				(font
					(size 1.27 1.27)
					(thickness 0.15)
				)
			)
		)
		(property "Footprint" ""
			(at 349.25 232.41 0)
			(effects
				(font
					(size 1.27 1.27)
					(thickness 0.15)
				)
				(justify left bottom)
				(hide yes)
			)
		)
		(property "Datasheet" ""
			(at 349.25 237.49 0)
			(effects
				(font
					(size 1.27 1.27)
					(thickness 0.15)
				)
				(justify left bottom)
				(hide yes)
			)
		)
		(property "Description" ""
			(at 340.36 224.79 0)
			(effects
				(font
					(size 1.27 1.27)
				)
				(hide yes)
			)
		)
		(property "Author" "Antmicro"
			(at 349.25 232.41 0)
			(effects
				(font
					(size 1.27 1.27)
					(thickness 0.15)
				)
				(justify left bottom)
				(hide yes)
			)
		)
		(property "License" "Apache-2.0"
			(at 349.25 234.95 0)
			(effects
				(font
					(size 1.27 1.27)
					(thickness 0.15)
				)
				(justify left bottom)
				(hide yes)
			)
		)
		(pin "1"
		)
		(instances
			(project "gmsl-deserializer"
				(path ""
					(reference "#PWR056")
					(unit 1)
				)
			)
		)
	)
	(symbol
		(lib_id "antmicropower:+5V")
		(at 388.62 46.99 0)
		(unit 1)
		(exclude_from_sim no)
		(in_bom yes)
		(on_board yes)
		(dnp no)
		(property "Reference" "#PWR0129"
			(at 403.86 49.53 0)
			(effects
				(font
					(size 1.27 1.27)
					(thickness 0.15)
				)
				(justify left bottom)
				(hide yes)
			)
		)
		(property "Value" "+5V"
			(at 388.62 43.18 0)
			(effects
				(font
					(size 1.27 1.27)
					(thickness 0.15)
				)
			)
		)
		(property "Footprint" ""
			(at 403.86 54.61 0)
			(effects
				(font
					(size 1.27 1.27)
					(thickness 0.15)
				)
				(justify left bottom)
				(hide yes)
			)
		)
		(property "Datasheet" ""
			(at 403.86 57.15 0)
			(effects
				(font
					(size 1.27 1.27)
					(thickness 0.15)
				)
				(justify left bottom)
				(hide yes)
			)
		)
		(property "Description" ""
			(at 388.62 46.99 0)
			(effects
				(font
					(size 1.27 1.27)
				)
				(hide yes)
			)
		)
		(property "Author" "Antmicro"
			(at 403.86 54.61 0)
			(effects
				(font
					(size 1.27 1.27)
					(thickness 0.15)
				)
				(justify left bottom)
				(hide yes)
			)
		)
		(property "License" "Apache-2.0"
			(at 403.86 57.15 0)
			(effects
				(font
					(size 1.27 1.27)
					(thickness 0.15)
				)
				(justify left bottom)
				(hide yes)
			)
		)
		(pin "1"
		)
		(instances
			(project "gmsl-deserializer"
				(path ""
					(reference "#PWR0129")
					(unit 1)
				)
			)
		)
	)
	(symbol
		(lib_id "antmicroCapacitors0402:C_22u_0402")
		(at 349.25 149.86 90)
		(unit 1)
		(exclude_from_sim no)
		(in_bom yes)
		(on_board yes)
		(dnp no)
		(fields_autoplaced yes)
		(property "Reference" "C25"
			(at 352.425 146.0435 90)
			(effects
				(font
					(size 1.27 1.27)
					(thickness 0.15)
				)
				(justify right)
			)
		)
		(property "Value" "C_22u_0402"
			(at 359.41 129.54 0)
			(effects
				(font
					(size 1.27 1.27)
					(thickness 0.15)
				)
				(justify left bottom)
				(hide yes)
			)
		)
		(property "Footprint" "antmicro-footprints:C_0402_1005Metric"
			(at 361.95 129.54 0)
			(effects
				(font
					(size 1.27 1.27)
					(thickness 0.15)
				)
				(justify left bottom)
				(hide yes)
			)
		)
		(property "Datasheet" "https://www.murata.com/products/productdetail?partno=GRM158R60J226ME01%23"
			(at 364.49 129.54 0)
			(effects
				(font
					(size 1.27 1.27)
					(thickness 0.15)
				)
				(justify left bottom)
				(hide yes)
			)
		)
		(property "Description" "SMD Multilayer Ceramic Capacitor, 22 uF, 4 V, 0402 [1005 Metric], X6S"
			(at 349.25 149.86 0)
			(effects
				(font
					(size 1.27 1.27)
				)
				(hide yes)
			)
		)
		(property "MPN" "GRM158R60J226ME01D"
			(at 367.03 129.54 0)
			(effects
				(font
					(size 1.27 1.27)
					(thickness 0.15)
				)
				(justify left bottom)
				(hide yes)
			)
		)
		(property "Manufacturer" "Murata"
			(at 369.57 129.54 0)
			(effects
				(font
					(size 1.27 1.27)
					(thickness 0.15)
				)
				(justify left bottom)
				(hide yes)
			)
		)
		(property "License" "Apache-2.0"
			(at 372.11 129.54 0)
			(effects
				(font
					(size 1.27 1.27)
					(thickness 0.15)
				)
				(justify left bottom)
				(hide yes)
			)
		)
		(property "Author" "Antmicro"
			(at 374.65 129.54 0)
			(effects
				(font
					(size 1.27 1.27)
					(thickness 0.15)
				)
				(justify left bottom)
				(hide yes)
			)
		)
		(property "Val" "22u"
			(at 352.425 148.5835 90)
			(effects
				(font
					(size 1.27 1.27)
					(thickness 0.15)
				)
				(justify right)
			)
		)
		(property "Voltage" ""
			(at 377.19 129.54 0)
			(effects
				(font
					(size 1.27 1.27)
				)
				(justify left bottom)
				(hide yes)
			)
		)
		(property "Dielectric" ""
			(at 379.73 129.54 0)
			(effects
				(font
					(size 1.27 1.27)
				)
				(justify left bottom)
				(hide yes)
			)
		)
		(pin "1"
		)
		(pin "2"
		)
		(instances
			(project "gmsl-deserializer"
				(path ""
					(reference "C25")
					(unit 1)
				)
			)
		)
	)
	(symbol
		(lib_id "antmicroResistors0402:R_5k1_0402")
		(at 121.92 149.86 0)
		(unit 1)
		(exclude_from_sim no)
		(in_bom yes)
		(on_board yes)
		(dnp no)
		(fields_autoplaced yes)
		(property "Reference" "R27"
			(at 124.46 144.145 0)
			(effects
				(font
					(size 1.27 1.27)
					(thickness 0.15)
				)
			)
		)
		(property "Value" "R_5k1_0402"
			(at 142.24 162.56 0)
			(effects
				(font
					(size 1.27 1.27)
					(thickness 0.15)
				)
				(justify left bottom)
				(hide yes)
			)
		)
		(property "Footprint" "antmicro-footprints:R_0402_1005Metric"
			(at 142.24 165.1 0)
			(effects
				(font
					(size 1.27 1.27)
					(thickness 0.15)
				)
				(justify left bottom)
				(hide yes)
			)
		)
		(property "Datasheet" "https://www.bourns.com/docs/product-datasheets/cr.pdf"
			(at 142.24 167.64 0)
			(effects
				(font
					(size 1.27 1.27)
					(thickness 0.15)
				)
				(justify left bottom)
				(hide yes)
			)
		)
		(property "Description" "SMD Chip Resistor, 5.1 kohm, ± 1%, 63 mW, 0402 [1005 Metric], Thick Film, General Purpose"
			(at 121.92 149.86 0)
			(effects
				(font
					(size 1.27 1.27)
				)
				(hide yes)
			)
		)
		(property "MPN" "CR0402-FX-5101GLF"
			(at 142.24 170.18 0)
			(effects
				(font
					(size 1.27 1.27)
					(thickness 0.15)
				)
				(justify left bottom)
				(hide yes)
			)
		)
		(property "Manufacturer" "Bourns"
			(at 142.24 172.72 0)
			(effects
				(font
					(size 1.27 1.27)
					(thickness 0.15)
				)
				(justify left bottom)
				(hide yes)
			)
		)
		(property "License" "Apache-2.0"
			(at 142.24 175.26 0)
			(effects
				(font
					(size 1.27 1.27)
					(thickness 0.15)
				)
				(justify left bottom)
				(hide yes)
			)
		)
		(property "Author" "Antmicro"
			(at 142.24 177.8 0)
			(effects
				(font
					(size 1.27 1.27)
					(thickness 0.15)
				)
				(justify left bottom)
				(hide yes)
			)
		)
		(property "Val" "5k1"
			(at 124.46 146.685 0)
			(effects
				(font
					(size 1.27 1.27)
					(thickness 0.15)
				)
			)
		)
		(property "Tolerance" "1%"
			(at 142.24 160.02 0)
			(effects
				(font
					(size 1.27 1.27)
				)
				(justify left bottom)
				(hide yes)
			)
		)
		(pin "1"
		)
		(pin "2"
		)
		(instances
			(project "gmsl-deserializer"
				(path ""
					(reference "R27")
					(unit 1)
				)
			)
		)
	)
	(symbol
		(lib_id "antmicroTestPoints:TP_0.75mm_SMD")
		(at 180.34 228.6 90)
		(unit 1)
		(exclude_from_sim no)
		(in_bom yes)
		(on_board yes)
		(dnp no)
		(property "Reference" "TP11"
			(at 179.07 223.52 90)
			(effects
				(font
					(size 1.27 1.27)
					(thickness 0.15)
				)
				(justify right)
			)
		)
		(property "Value" "TP_0.75mm_SMD"
			(at 184.15 217.805 0)
			(effects
				(font
					(size 1.27 1.27)
					(thickness 0.15)
				)
				(justify left bottom)
				(hide yes)
			)
		)
		(property "Footprint" "antmicro-footprints:TP_SMD_0.75mm"
			(at 186.69 217.805 0)
			(effects
				(font
					(size 1.27 1.27)
					(thickness 0.15)
				)
				(justify left bottom)
				(hide yes)
			)
		)
		(property "Datasheet" ""
			(at 193.04 210.82 0)
			(effects
				(font
					(size 1.27 1.27)
					(thickness 0.15)
				)
				(justify left bottom)
				(hide yes)
			)
		)
		(property "Description" "SMT test point"
			(at 180.34 228.6 0)
			(effects
				(font
					(size 1.27 1.27)
				)
				(hide yes)
			)
		)
		(property "MPN" ""
			(at 191.77 217.805 0)
			(effects
				(font
					(size 1.27 1.27)
					(thickness 0.15)
				)
				(justify left bottom)
				(hide yes)
			)
		)
		(property "Manufacturer" ""
			(at 186.69 217.805 0)
			(effects
				(font
					(size 1.27 1.27)
					(thickness 0.15)
				)
				(justify left bottom)
				(hide yes)
			)
		)
		(property "Author" "Antmicro"
			(at 189.23 217.805 0)
			(effects
				(font
					(size 1.27 1.27)
					(thickness 0.15)
				)
				(justify left bottom)
				(hide yes)
			)
		)
		(property "License" "Apache-2.0"
			(at 191.77 217.805 0)
			(effects
				(font
					(size 1.27 1.27)
					(thickness 0.15)
				)
				(justify left bottom)
				(hide yes)
			)
		)
		(pin "1"
		)
		(instances
			(project "gmsl-deserializer"
				(path ""
					(reference "TP11")
					(unit 1)
				)
			)
		)
	)
	(symbol
		(lib_id "antmicropower:GND")
		(at 388.62 80.01 0)
		(unit 1)
		(exclude_from_sim no)
		(in_bom yes)
		(on_board yes)
		(dnp no)
		(property "Reference" "#PWR0128"
			(at 397.51 82.55 0)
			(effects
				(font
					(size 1.27 1.27)
					(thickness 0.15)
				)
				(justify left bottom)
				(hide yes)
			)
		)
		(property "Value" "GND"
			(at 388.62 83.82 0)
			(effects
				(font
					(size 1.27 1.27)
					(thickness 0.15)
				)
			)
		)
		(property "Footprint" ""
			(at 397.51 87.63 0)
			(effects
				(font
					(size 1.27 1.27)
					(thickness 0.15)
				)
				(justify left bottom)
				(hide yes)
			)
		)
		(property "Datasheet" ""
			(at 397.51 92.71 0)
			(effects
				(font
					(size 1.27 1.27)
					(thickness 0.15)
				)
				(justify left bottom)
				(hide yes)
			)
		)
		(property "Description" ""
			(at 388.62 80.01 0)
			(effects
				(font
					(size 1.27 1.27)
				)
				(hide yes)
			)
		)
		(property "Author" "Antmicro"
			(at 397.51 87.63 0)
			(effects
				(font
					(size 1.27 1.27)
					(thickness 0.15)
				)
				(justify left bottom)
				(hide yes)
			)
		)
		(property "License" "Apache-2.0"
			(at 397.51 90.17 0)
			(effects
				(font
					(size 1.27 1.27)
					(thickness 0.15)
				)
				(justify left bottom)
				(hide yes)
			)
		)
		(pin "1"
		)
		(instances
			(project "gmsl-deserializer"
				(path ""
					(reference "#PWR0128")
					(unit 1)
				)
			)
		)
	)
	(symbol
		(lib_id "antmicroFixedInductors:L_1u_2.6A_0806")
		(at 321.31 132.08 0)
		(unit 1)
		(exclude_from_sim no)
		(in_bom yes)
		(on_board yes)
		(dnp no)
		(fields_autoplaced yes)
		(property "Reference" "L19"
			(at 323.85 126.365 0)
			(effects
				(font
					(size 1.27 1.27)
					(thickness 0.15)
				)
			)
		)
		(property "Value" "L_1u_2.6A_0806"
			(at 335.28 134.62 0)
			(effects
				(font
					(size 1.27 1.27)
					(thickness 0.15)
				)
				(justify left bottom)
				(hide yes)
			)
		)
		(property "Footprint" "antmicro-footprints:L_0806_2016Metric"
			(at 335.28 139.7 0)
			(effects
				(font
					(size 1.27 1.27)
					(thickness 0.15)
				)
				(justify left bottom)
				(hide yes)
			)
		)
		(property "Datasheet" "https://www.bourns.com/docs/Product-Datasheets/SRP2010.pdf"
			(at 335.28 142.24 0)
			(effects
				(font
					(size 1.27 1.27)
					(thickness 0.15)
				)
				(justify left bottom)
				(hide yes)
			)
		)
		(property "Description" "Wirewound Inductor, 1 µH, 0.072 ohm, 2.6 A, SRP2010"
			(at 321.31 132.08 0)
			(effects
				(font
					(size 1.27 1.27)
				)
				(hide yes)
			)
		)
		(property "Val" "1u/2.6A"
			(at 323.85 128.905 0)
			(effects
				(font
					(size 1.27 1.27)
					(thickness 0.15)
				)
			)
		)
		(property "Manufacturer" "Bourns"
			(at 335.28 144.78 0)
			(effects
				(font
					(size 1.27 1.27)
					(thickness 0.15)
				)
				(justify left bottom)
				(hide yes)
			)
		)
		(property "MPN" "SRP2010-1R0M"
			(at 335.28 147.32 0)
			(effects
				(font
					(size 1.27 1.27)
					(thickness 0.15)
				)
				(justify left bottom)
				(hide yes)
			)
		)
		(property "ISat" "2.9 A"
			(at 335.28 148.59 0)
			(effects
				(font
					(size 1.27 1.27)
				)
				(justify left)
				(hide yes)
			)
		)
		(property "IMax" "2.6 A"
			(at 335.28 152.4 0)
			(effects
				(font
					(size 1.27 1.27)
					(thickness 0.15)
				)
				(justify left bottom)
				(hide yes)
			)
		)
		(property "Size" "2.0x1.6"
			(at 335.28 154.94 0)
			(effects
				(font
					(size 1.27 1.27)
					(thickness 0.15)
				)
				(justify left bottom)
				(hide yes)
			)
		)
		(property "Author" "Antmicro"
			(at 335.28 157.48 0)
			(effects
				(font
					(size 1.27 1.27)
					(thickness 0.15)
				)
				(justify left bottom)
				(hide yes)
			)
		)
		(property "License" "Apache-2.0"
			(at 335.28 160.02 0)
			(effects
				(font
					(size 1.27 1.27)
					(thickness 0.15)
				)
				(justify left bottom)
				(hide yes)
			)
		)
		(pin "1"
		)
		(pin "2"
		)
		(instances
			(project "gmsl-deserializer"
				(path ""
					(reference "L19")
					(unit 1)
				)
			)
		)
	)
	(symbol
		(lib_id "antmicropower:+12V")
		(at 81.28 113.03 0)
		(unit 1)
		(exclude_from_sim no)
		(in_bom yes)
		(on_board yes)
		(dnp no)
		(fields_autoplaced yes)
		(property "Reference" "#PWR026"
			(at 81.28 116.84 0)
			(effects
				(font
					(size 1.27 1.27)
				)
				(hide yes)
			)
		)
		(property "Value" "+12V"
			(at 81.28 107.95 0)
			(effects
				(font
					(size 1.27 1.27)
				)
			)
		)
		(property "Footprint" ""
			(at 81.28 113.03 0)
			(effects
				(font
					(size 1.27 1.27)
				)
				(hide yes)
			)
		)
		(property "Datasheet" ""
			(at 81.28 113.03 0)
			(effects
				(font
					(size 1.27 1.27)
				)
				(hide yes)
			)
		)
		(property "Description" ""
			(at 81.28 113.03 0)
			(effects
				(font
					(size 1.27 1.27)
				)
				(hide yes)
			)
		)
		(pin "1"
		)
		(instances
			(project "gmsl-deserializer"
				(path ""
					(reference "#PWR026")
					(unit 1)
				)
			)
		)
	)
	(symbol
		(lib_id "antmicroCapacitors0402:C_100n_0402")
		(at 340.36 223.52 90)
		(unit 1)
		(exclude_from_sim no)
		(in_bom yes)
		(on_board yes)
		(dnp no)
		(property "Reference" "C23"
			(at 341.63 219.075 90)
			(effects
				(font
					(size 1.27 1.27)
					(thickness 0.15)
				)
				(justify right)
			)
		)
		(property "Value" "C_100n_0402"
			(at 350.52 203.2 0)
			(effects
				(font
					(size 1.27 1.27)
					(thickness 0.15)
				)
				(justify left bottom)
				(hide yes)
			)
		)
		(property "Footprint" "antmicro-footprints:C_0402_1005Metric"
			(at 353.06 203.2 0)
			(effects
				(font
					(size 1.27 1.27)
					(thickness 0.15)
				)
				(justify left bottom)
				(hide yes)
			)
		)
		(property "Datasheet" "https://www.murata.com/products/productdetail?partno=GRM155R61H104KE14%23"
			(at 355.6 203.2 0)
			(effects
				(font
					(size 1.27 1.27)
					(thickness 0.15)
				)
				(justify left bottom)
				(hide yes)
			)
		)
		(property "Description" "SMD Multilayer Ceramic Capacitor, 0.1 µF, 50 V, 0402 [1005 Metric], ± 10%, X5R, GRM Series"
			(at 340.36 223.52 0)
			(effects
				(font
					(size 1.27 1.27)
				)
				(hide yes)
			)
		)
		(property "MPN" "GRM155R61H104KE14D"
			(at 358.14 203.2 0)
			(effects
				(font
					(size 1.27 1.27)
					(thickness 0.15)
				)
				(justify left bottom)
				(hide yes)
			)
		)
		(property "Manufacturer" "Murata"
			(at 360.68 203.2 0)
			(effects
				(font
					(size 1.27 1.27)
					(thickness 0.15)
				)
				(justify left bottom)
				(hide yes)
			)
		)
		(property "License" "Apache-2.0"
			(at 363.22 203.2 0)
			(effects
				(font
					(size 1.27 1.27)
					(thickness 0.15)
				)
				(justify left bottom)
				(hide yes)
			)
		)
		(property "Author" "Antmicro"
			(at 365.76 203.2 0)
			(effects
				(font
					(size 1.27 1.27)
					(thickness 0.15)
				)
				(justify left bottom)
				(hide yes)
			)
		)
		(property "Val" "100n"
			(at 341.63 222.885 90)
			(effects
				(font
					(size 1.27 1.27)
					(thickness 0.15)
				)
				(justify right)
			)
		)
		(property "Voltage" "50V"
			(at 368.3 203.2 0)
			(effects
				(font
					(size 1.27 1.27)
				)
				(justify left bottom)
				(hide yes)
			)
		)
		(property "Dielectric" "X5R"
			(at 370.84 203.2 0)
			(effects
				(font
					(size 1.27 1.27)
				)
				(justify left bottom)
				(hide yes)
			)
		)
		(pin "1"
		)
		(pin "2"
		)
		(instances
			(project "gmsl-deserializer"
				(path ""
					(reference "C23")
					(unit 1)
				)
			)
		)
	)
	(symbol
		(lib_id "antmicroResistors0402:R_120k_0402")
		(at 223.52 237.49 0)
		(unit 1)
		(exclude_from_sim no)
		(in_bom yes)
		(on_board yes)
		(dnp no)
		(property "Reference" "R30"
			(at 224.155 234.95 0)
			(effects
				(font
					(size 1.27 1.27)
					(thickness 0.15)
				)
			)
		)
		(property "Value" "R_120k_0402"
			(at 243.84 250.19 0)
			(effects
				(font
					(size 1.27 1.27)
					(thickness 0.15)
				)
				(justify left bottom)
				(hide yes)
			)
		)
		(property "Footprint" "antmicro-footprints:R_0402_1005Metric"
			(at 243.84 252.73 0)
			(effects
				(font
					(size 1.27 1.27)
					(thickness 0.15)
				)
				(justify left bottom)
				(hide yes)
			)
		)
		(property "Datasheet" "https://www.bourns.com/docs/product-datasheets/cr.pdf"
			(at 243.84 255.27 0)
			(effects
				(font
					(size 1.27 1.27)
					(thickness 0.15)
				)
				(justify left bottom)
				(hide yes)
			)
		)
		(property "Description" "SMD Chip Resistor, 120 kohm, ± 1%, 100 mW, 0402 [1005 Metric], Thick Film, Precision"
			(at 223.52 237.49 0)
			(effects
				(font
					(size 1.27 1.27)
				)
				(hide yes)
			)
		)
		(property "MPN" "CR0402-FX-1203GLF"
			(at 243.84 257.81 0)
			(effects
				(font
					(size 1.27 1.27)
					(thickness 0.15)
				)
				(justify left bottom)
				(hide yes)
			)
		)
		(property "Manufacturer" "Bourns"
			(at 243.84 260.35 0)
			(effects
				(font
					(size 1.27 1.27)
					(thickness 0.15)
				)
				(justify left bottom)
				(hide yes)
			)
		)
		(property "License" "Apache-2.0"
			(at 243.84 262.89 0)
			(effects
				(font
					(size 1.27 1.27)
					(thickness 0.15)
				)
				(justify left bottom)
				(hide yes)
			)
		)
		(property "Author" "Antmicro"
			(at 243.84 265.43 0)
			(effects
				(font
					(size 1.27 1.27)
					(thickness 0.15)
				)
				(justify left bottom)
				(hide yes)
			)
		)
		(property "Val" "120k"
			(at 228.6 234.95 0)
			(effects
				(font
					(size 1.27 1.27)
					(thickness 0.15)
				)
			)
		)
		(property "Tolerance" "1%"
			(at 243.84 247.65 0)
			(effects
				(font
					(size 1.27 1.27)
				)
				(justify left bottom)
				(hide yes)
			)
		)
		(pin "1"
		)
		(pin "2"
		)
		(instances
			(project "gmsl-deserializer"
				(path ""
					(reference "R30")
					(unit 1)
				)
			)
		)
	)
	(symbol
		(lib_id "antmicroResistors0402:R_10k_0402")
		(at 327.66 72.39 90)
		(unit 1)
		(exclude_from_sim no)
		(in_bom yes)
		(on_board yes)
		(dnp no)
		(fields_autoplaced yes)
		(property "Reference" "R36"
			(at 329.565 68.5799 90)
			(effects
				(font
					(size 1.27 1.27)
					(thickness 0.15)
				)
				(justify right)
			)
		)
		(property "Value" "R_10k_0402"
			(at 340.36 52.07 0)
			(effects
				(font
					(size 1.27 1.27)
					(thickness 0.15)
				)
				(justify left bottom)
				(hide yes)
			)
		)
		(property "Footprint" "antmicro-footprints:R_0402_1005Metric"
			(at 342.9 52.07 0)
			(effects
				(font
					(size 1.27 1.27)
					(thickness 0.15)
				)
				(justify left bottom)
				(hide yes)
			)
		)
		(property "Datasheet" "https://www.bourns.com/docs/product-datasheets/cr.pdf"
			(at 345.44 52.07 0)
			(effects
				(font
					(size 1.27 1.27)
					(thickness 0.15)
				)
				(justify left bottom)
				(hide yes)
			)
		)
		(property "Description" "SMD Chip Resistor, 10 kohm, ± 1%, 62.5 mW, 0402 [1005 Metric], Thick Film, General Purpose"
			(at 327.66 72.39 0)
			(effects
				(font
					(size 1.27 1.27)
				)
				(hide yes)
			)
		)
		(property "MPN" "CR0402-FX-1002GLF"
			(at 347.98 52.07 0)
			(effects
				(font
					(size 1.27 1.27)
					(thickness 0.15)
				)
				(justify left bottom)
				(hide yes)
			)
		)
		(property "Manufacturer" "Bourns"
			(at 350.52 52.07 0)
			(effects
				(font
					(size 1.27 1.27)
					(thickness 0.15)
				)
				(justify left bottom)
				(hide yes)
			)
		)
		(property "License" "Apache-2.0"
			(at 353.06 52.07 0)
			(effects
				(font
					(size 1.27 1.27)
					(thickness 0.15)
				)
				(justify left bottom)
				(hide yes)
			)
		)
		(property "Author" "Antmicro"
			(at 355.6 52.07 0)
			(effects
				(font
					(size 1.27 1.27)
					(thickness 0.15)
				)
				(justify left bottom)
				(hide yes)
			)
		)
		(property "Val" "10k"
			(at 329.565 71.1199 90)
			(effects
				(font
					(size 1.27 1.27)
					(thickness 0.15)
				)
				(justify right)
			)
		)
		(property "Tolerance" "1%"
			(at 337.82 52.07 0)
			(effects
				(font
					(size 1.27 1.27)
				)
				(justify left bottom)
				(hide yes)
			)
		)
		(pin "1"
		)
		(pin "2"
		)
		(instances
			(project "gmsl-deserializer"
				(path ""
					(reference "R36")
					(unit 1)
				)
			)
		)
	)
	(symbol
		(lib_id "antmicropower:PWR_FLAG")
		(at 119.38 223.52 0)
		(unit 1)
		(exclude_from_sim no)
		(in_bom yes)
		(on_board yes)
		(dnp no)
		(property "Reference" "#FLG0104"
			(at 119.38 221.615 0)
			(effects
				(font
					(size 1.27 1.27)
				)
				(hide yes)
			)
		)
		(property "Value" "PWR_FLAG"
			(at 119.38 219.71 0)
			(effects
				(font
					(size 1.27 1.27)
				)
			)
		)
		(property "Footprint" ""
			(at 119.38 223.52 0)
			(effects
				(font
					(size 1.27 1.27)
				)
				(hide yes)
			)
		)
		(property "Datasheet" ""
			(at 119.38 223.52 0)
			(effects
				(font
					(size 1.27 1.27)
				)
				(hide yes)
			)
		)
		(property "Description" ""
			(at 119.38 223.52 0)
			(effects
				(font
					(size 1.27 1.27)
				)
				(hide yes)
			)
		)
		(pin "1"
		)
		(instances
			(project "gmsl-deserializer"
				(path ""
					(reference "#FLG0104")
					(unit 1)
				)
			)
		)
	)
	(symbol
		(lib_id "antmicroResistors0402:R_470R_0402")
		(at 388.62 134.62 90)
		(unit 1)
		(exclude_from_sim no)
		(in_bom yes)
		(on_board yes)
		(dnp no)
		(fields_autoplaced yes)
		(property "Reference" "R80"
			(at 391.16 130.8099 90)
			(effects
				(font
					(size 1.27 1.27)
					(thickness 0.15)
				)
				(justify right)
			)
		)
		(property "Value" "R_470R_0402"
			(at 401.32 114.3 0)
			(effects
				(font
					(size 1.27 1.27)
					(thickness 0.15)
				)
				(justify left bottom)
				(hide yes)
			)
		)
		(property "Footprint" "antmicro-footprints:R_0402_1005Metric"
			(at 403.86 114.3 0)
			(effects
				(font
					(size 1.27 1.27)
					(thickness 0.15)
				)
				(justify left bottom)
				(hide yes)
			)
		)
		(property "Datasheet" "https://www.bourns.com/docs/product-datasheets/cr.pdf"
			(at 406.4 114.3 0)
			(effects
				(font
					(size 1.27 1.27)
					(thickness 0.15)
				)
				(justify left bottom)
				(hide yes)
			)
		)
		(property "Description" "SMD Chip Resistor, 470 ohm, ± 1%, 62.5 mW, 0402 [1005 Metric], Thick Film, General Purpose"
			(at 388.62 134.62 0)
			(effects
				(font
					(size 1.27 1.27)
				)
				(hide yes)
			)
		)
		(property "MPN" "CR0402-FX-4700GLF"
			(at 408.94 114.3 0)
			(effects
				(font
					(size 1.27 1.27)
					(thickness 0.15)
				)
				(justify left bottom)
				(hide yes)
			)
		)
		(property "Manufacturer" "Bourns"
			(at 411.48 114.3 0)
			(effects
				(font
					(size 1.27 1.27)
					(thickness 0.15)
				)
				(justify left bottom)
				(hide yes)
			)
		)
		(property "License" "Apache-2.0"
			(at 414.02 114.3 0)
			(effects
				(font
					(size 1.27 1.27)
					(thickness 0.15)
				)
				(justify left bottom)
				(hide yes)
			)
		)
		(property "Author" "Antmicro"
			(at 416.56 114.3 0)
			(effects
				(font
					(size 1.27 1.27)
					(thickness 0.15)
				)
				(justify left bottom)
				(hide yes)
			)
		)
		(property "Val" "470R"
			(at 391.16 133.3499 90)
			(effects
				(font
					(size 1.27 1.27)
					(thickness 0.15)
				)
				(justify right)
			)
		)
		(property "Tolerance" "1%"
			(at 398.78 114.3 0)
			(effects
				(font
					(size 1.27 1.27)
				)
				(justify left bottom)
				(hide yes)
			)
		)
		(pin "1"
		)
		(pin "2"
		)
		(instances
			(project "gmsl-deserializer"
				(path ""
					(reference "R80")
					(unit 1)
				)
			)
		)
	)
	(symbol
		(lib_id "antmicropower:GND")
		(at 81.28 71.12 0)
		(unit 1)
		(exclude_from_sim no)
		(in_bom yes)
		(on_board yes)
		(dnp no)
		(property "Reference" "#PWR023"
			(at 90.17 73.66 0)
			(effects
				(font
					(size 1.27 1.27)
					(thickness 0.15)
				)
				(justify left bottom)
				(hide yes)
			)
		)
		(property "Value" "GND"
			(at 81.28 74.93 0)
			(effects
				(font
					(size 1.27 1.27)
					(thickness 0.15)
				)
			)
		)
		(property "Footprint" ""
			(at 90.17 78.74 0)
			(effects
				(font
					(size 1.27 1.27)
					(thickness 0.15)
				)
				(justify left bottom)
				(hide yes)
			)
		)
		(property "Datasheet" ""
			(at 90.17 83.82 0)
			(effects
				(font
					(size 1.27 1.27)
					(thickness 0.15)
				)
				(justify left bottom)
				(hide yes)
			)
		)
		(property "Description" ""
			(at 81.28 71.12 0)
			(effects
				(font
					(size 1.27 1.27)
				)
				(hide yes)
			)
		)
		(property "Author" "Antmicro"
			(at 90.17 78.74 0)
			(effects
				(font
					(size 1.27 1.27)
					(thickness 0.15)
				)
				(justify left bottom)
				(hide yes)
			)
		)
		(property "License" "Apache-2.0"
			(at 90.17 81.28 0)
			(effects
				(font
					(size 1.27 1.27)
					(thickness 0.15)
				)
				(justify left bottom)
				(hide yes)
			)
		)
		(pin "1"
		)
		(instances
			(project "gmsl-deserializer"
				(path ""
					(reference "#PWR023")
					(unit 1)
				)
			)
		)
	)
	(symbol
		(lib_id "antmicroResistors0402:R_100k_0402")
		(at 81.28 248.92 90)
		(unit 1)
		(exclude_from_sim no)
		(in_bom yes)
		(on_board yes)
		(dnp no)
		(fields_autoplaced yes)
		(property "Reference" "R17"
			(at 83.82 245.1099 90)
			(effects
				(font
					(size 1.27 1.27)
					(thickness 0.15)
				)
				(justify right)
			)
		)
		(property "Value" "R_100k_0402"
			(at 93.98 228.6 0)
			(effects
				(font
					(size 1.27 1.27)
					(thickness 0.15)
				)
				(justify left bottom)
				(hide yes)
			)
		)
		(property "Footprint" "antmicro-footprints:R_0402_1005Metric"
			(at 96.52 228.6 0)
			(effects
				(font
					(size 1.27 1.27)
					(thickness 0.15)
				)
				(justify left bottom)
				(hide yes)
			)
		)
		(property "Datasheet" "https://www.bourns.com/docs/product-datasheets/cr.pdf"
			(at 99.06 228.6 0)
			(effects
				(font
					(size 1.27 1.27)
					(thickness 0.15)
				)
				(justify left bottom)
				(hide yes)
			)
		)
		(property "Description" "SMD Chip Resistor, 100 kohm, ± 1%, 62.5 mW, 0402 [1005 Metric], Thick Film, General Purpose"
			(at 81.28 248.92 0)
			(effects
				(font
					(size 1.27 1.27)
				)
				(hide yes)
			)
		)
		(property "MPN" "CR0402-FX-1003GLF"
			(at 101.6 228.6 0)
			(effects
				(font
					(size 1.27 1.27)
					(thickness 0.15)
				)
				(justify left bottom)
				(hide yes)
			)
		)
		(property "Manufacturer" "Bourns"
			(at 104.14 228.6 0)
			(effects
				(font
					(size 1.27 1.27)
					(thickness 0.15)
				)
				(justify left bottom)
				(hide yes)
			)
		)
		(property "License" "Apache-2.0"
			(at 106.68 228.6 0)
			(effects
				(font
					(size 1.27 1.27)
					(thickness 0.15)
				)
				(justify left bottom)
				(hide yes)
			)
		)
		(property "Author" "Antmicro"
			(at 109.22 228.6 0)
			(effects
				(font
					(size 1.27 1.27)
					(thickness 0.15)
				)
				(justify left bottom)
				(hide yes)
			)
		)
		(property "Val" "100k"
			(at 83.82 247.6499 90)
			(effects
				(font
					(size 1.27 1.27)
					(thickness 0.15)
				)
				(justify right)
			)
		)
		(property "Tolerance" "1%"
			(at 91.44 228.6 0)
			(effects
				(font
					(size 1.27 1.27)
				)
				(justify left bottom)
				(hide yes)
			)
		)
		(pin "1"
		)
		(pin "2"
		)
		(instances
			(project "gmsl-deserializer"
				(path ""
					(reference "R17")
					(unit 1)
				)
			)
		)
	)
	(symbol
		(lib_id "antmicroResistors0402:R_1k65_0402")
		(at 129.54 240.03 90)
		(unit 1)
		(exclude_from_sim no)
		(in_bom yes)
		(on_board yes)
		(dnp no)
		(fields_autoplaced yes)
		(property "Reference" "R75"
			(at 132.08 236.22 90)
			(effects
				(font
					(size 1.27 1.27)
					(thickness 0.15)
				)
				(justify right)
			)
		)
		(property "Value" "R_1k65_0402"
			(at 142.24 219.71 0)
			(effects
				(font
					(size 1.27 1.27)
					(thickness 0.15)
				)
				(justify left bottom)
				(hide yes)
			)
		)
		(property "Footprint" "antmicro-footprints:R_0402_1005Metric"
			(at 144.78 219.71 0)
			(effects
				(font
					(size 1.27 1.27)
					(thickness 0.15)
				)
				(justify left bottom)
				(hide yes)
			)
		)
		(property "Datasheet" "https://www.farnell.com/datasheets/3795017.pdf"
			(at 147.32 219.71 0)
			(effects
				(font
					(size 1.27 1.27)
					(thickness 0.15)
				)
				(justify left bottom)
				(hide yes)
			)
		)
		(property "Description" "SMD Chip Resistor, 1.65 kohm, ± 1%, 63 mW, 0402 [1005 Metric], Thick Film, General Purpose"
			(at 129.54 240.03 0)
			(effects
				(font
					(size 1.27 1.27)
				)
				(hide yes)
			)
		)
		(property "MPN" "RC0402FR-071K65L"
			(at 149.86 219.71 0)
			(effects
				(font
					(size 1.27 1.27)
					(thickness 0.15)
				)
				(justify left bottom)
				(hide yes)
			)
		)
		(property "Manufacturer" "YAGEO"
			(at 152.4 219.71 0)
			(effects
				(font
					(size 1.27 1.27)
					(thickness 0.15)
				)
				(justify left bottom)
				(hide yes)
			)
		)
		(property "License" "Apache-2.0"
			(at 154.94 219.71 0)
			(effects
				(font
					(size 1.27 1.27)
					(thickness 0.15)
				)
				(justify left bottom)
				(hide yes)
			)
		)
		(property "Author" "Antmicro"
			(at 157.48 219.71 0)
			(effects
				(font
					(size 1.27 1.27)
					(thickness 0.15)
				)
				(justify left bottom)
				(hide yes)
			)
		)
		(property "Val" "1k65"
			(at 132.08 238.76 90)
			(effects
				(font
					(size 1.27 1.27)
					(thickness 0.15)
				)
				(justify right)
			)
		)
		(property "Tolerance" "1%"
			(at 139.7 219.71 0)
			(effects
				(font
					(size 1.27 1.27)
				)
				(justify left bottom)
				(hide yes)
			)
		)
		(property "Public" ""
			(at 160.02 219.71 0)
			(effects
				(font
					(size 1.27 1.27)
				)
				(justify left bottom)
				(hide yes)
			)
		)
		(pin "1"
		)
		(pin "2"
		)
		(instances
			(project "gmsl-deserializer"
				(path ""
					(reference "R75")
					(unit 1)
				)
			)
		)
	)
	(symbol
		(lib_id "antmicroResistors0402:R_10k_0402")
		(at 346.71 214.63 90)
		(unit 1)
		(exclude_from_sim no)
		(in_bom yes)
		(on_board yes)
		(dnp no)
		(fields_autoplaced yes)
		(property "Reference" "R39"
			(at 348.615 210.8199 90)
			(effects
				(font
					(size 1.27 1.27)
					(thickness 0.15)
				)
				(justify right)
			)
		)
		(property "Value" "R_10k_0402"
			(at 359.41 194.31 0)
			(effects
				(font
					(size 1.27 1.27)
					(thickness 0.15)
				)
				(justify left bottom)
				(hide yes)
			)
		)
		(property "Footprint" "antmicro-footprints:R_0402_1005Metric"
			(at 361.95 194.31 0)
			(effects
				(font
					(size 1.27 1.27)
					(thickness 0.15)
				)
				(justify left bottom)
				(hide yes)
			)
		)
		(property "Datasheet" "https://www.bourns.com/docs/product-datasheets/cr.pdf"
			(at 364.49 194.31 0)
			(effects
				(font
					(size 1.27 1.27)
					(thickness 0.15)
				)
				(justify left bottom)
				(hide yes)
			)
		)
		(property "Description" "SMD Chip Resistor, 10 kohm, ± 1%, 62.5 mW, 0402 [1005 Metric], Thick Film, General Purpose"
			(at 346.71 214.63 0)
			(effects
				(font
					(size 1.27 1.27)
				)
				(hide yes)
			)
		)
		(property "MPN" "CR0402-FX-1002GLF"
			(at 367.03 194.31 0)
			(effects
				(font
					(size 1.27 1.27)
					(thickness 0.15)
				)
				(justify left bottom)
				(hide yes)
			)
		)
		(property "Manufacturer" "Bourns"
			(at 369.57 194.31 0)
			(effects
				(font
					(size 1.27 1.27)
					(thickness 0.15)
				)
				(justify left bottom)
				(hide yes)
			)
		)
		(property "License" "Apache-2.0"
			(at 372.11 194.31 0)
			(effects
				(font
					(size 1.27 1.27)
					(thickness 0.15)
				)
				(justify left bottom)
				(hide yes)
			)
		)
		(property "Author" "Antmicro"
			(at 374.65 194.31 0)
			(effects
				(font
					(size 1.27 1.27)
					(thickness 0.15)
				)
				(justify left bottom)
				(hide yes)
			)
		)
		(property "Val" "10k"
			(at 348.615 213.3599 90)
			(effects
				(font
					(size 1.27 1.27)
					(thickness 0.15)
				)
				(justify right)
			)
		)
		(property "Tolerance" "1%"
			(at 356.87 194.31 0)
			(effects
				(font
					(size 1.27 1.27)
				)
				(justify left bottom)
				(hide yes)
			)
		)
		(pin "1"
		)
		(pin "2"
		)
		(instances
			(project "gmsl-deserializer"
				(path ""
					(reference "R39")
					(unit 1)
				)
			)
		)
	)
	(symbol
		(lib_id "antmicropower:PWR_FLAG")
		(at 363.22 130.81 0)
		(unit 1)
		(exclude_from_sim no)
		(in_bom yes)
		(on_board yes)
		(dnp no)
		(property "Reference" "#FLG0106"
			(at 363.22 128.905 0)
			(effects
				(font
					(size 1.27 1.27)
				)
				(hide yes)
			)
		)
		(property "Value" "PWR_FLAG"
			(at 363.22 127 0)
			(effects
				(font
					(size 1.27 1.27)
				)
			)
		)
		(property "Footprint" ""
			(at 363.22 130.81 0)
			(effects
				(font
					(size 1.27 1.27)
				)
				(hide yes)
			)
		)
		(property "Datasheet" ""
			(at 363.22 130.81 0)
			(effects
				(font
					(size 1.27 1.27)
				)
				(hide yes)
			)
		)
		(property "Description" ""
			(at 363.22 130.81 0)
			(effects
				(font
					(size 1.27 1.27)
				)
				(hide yes)
			)
		)
		(pin "1"
		)
		(instances
			(project "gmsl-deserializer"
				(path ""
					(reference "#FLG0106")
					(unit 1)
				)
			)
		)
	)
	(symbol
		(lib_id "antmicropower:GND")
		(at 262.89 144.78 0)
		(unit 1)
		(exclude_from_sim no)
		(in_bom yes)
		(on_board yes)
		(dnp no)
		(property "Reference" "#PWR045"
			(at 271.78 147.32 0)
			(effects
				(font
					(size 1.27 1.27)
					(thickness 0.15)
				)
				(justify left bottom)
				(hide yes)
			)
		)
		(property "Value" "GND"
			(at 262.89 148.59 0)
			(effects
				(font
					(size 1.27 1.27)
					(thickness 0.15)
				)
			)
		)
		(property "Footprint" ""
			(at 271.78 152.4 0)
			(effects
				(font
					(size 1.27 1.27)
					(thickness 0.15)
				)
				(justify left bottom)
				(hide yes)
			)
		)
		(property "Datasheet" ""
			(at 271.78 157.48 0)
			(effects
				(font
					(size 1.27 1.27)
					(thickness 0.15)
				)
				(justify left bottom)
				(hide yes)
			)
		)
		(property "Description" ""
			(at 262.89 144.78 0)
			(effects
				(font
					(size 1.27 1.27)
				)
				(hide yes)
			)
		)
		(property "Author" "Antmicro"
			(at 271.78 152.4 0)
			(effects
				(font
					(size 1.27 1.27)
					(thickness 0.15)
				)
				(justify left bottom)
				(hide yes)
			)
		)
		(property "License" "Apache-2.0"
			(at 271.78 154.94 0)
			(effects
				(font
					(size 1.27 1.27)
					(thickness 0.15)
				)
				(justify left bottom)
				(hide yes)
			)
		)
		(pin "1"
		)
		(instances
			(project "gmsl-deserializer"
				(path ""
					(reference "#PWR045")
					(unit 1)
				)
			)
		)
	)
	(symbol
		(lib_id "antmicroLEDIndicationDiscrete:LED_G_0603_LTST-C190GKT")
		(at 129.54 232.41 270)
		(mirror x)
		(unit 1)
		(exclude_from_sim no)
		(in_bom yes)
		(on_board yes)
		(dnp no)
		(property "Reference" "D17"
			(at 132.08 229.87 90)
			(effects
				(font
					(size 1.27 1.27)
					(thickness 0.15)
				)
				(justify left)
			)
		)
		(property "Value" "LED_G_0603_LTST-C190GKT"
			(at 100.965 227.33 90)
			(effects
				(font
					(size 1.27 1.27)
					(thickness 0.15)
				)
				(justify left)
				(hide yes)
			)
		)
		(property "Footprint" "antmicro-footprints:LED_0603_1608Metric_G"
			(at 119.38 209.55 0)
			(effects
				(font
					(size 1.27 1.27)
					(thickness 0.15)
				)
				(justify left bottom)
				(hide yes)
			)
		)
		(property "Datasheet" "https://media.digikey.com/pdf/Data%20Sheets/Lite-On%20PDFs/LTST-C190GKT.pdf"
			(at 116.84 209.55 0)
			(effects
				(font
					(size 1.27 1.27)
					(thickness 0.15)
				)
				(justify left bottom)
				(hide yes)
			)
		)
		(property "Description" "LED, Green, SMD, 0603, 20 mA, 2.1 V, 569 nm"
			(at 129.54 232.41 0)
			(effects
				(font
					(size 1.27 1.27)
				)
				(hide yes)
			)
		)
		(property "MPN" "LTST-C190GKT"
			(at 132.08 231.14 90)
			(effects
				(font
					(size 1.27 1.27)
					(thickness 0.15)
				)
				(justify left bottom)
			)
		)
		(property "Manufacturer" "Lite-On"
			(at 111.76 209.55 0)
			(effects
				(font
					(size 1.27 1.27)
					(thickness 0.15)
				)
				(justify left bottom)
				(hide yes)
			)
		)
		(property "Author" "Antmicro"
			(at 109.22 209.55 0)
			(effects
				(font
					(size 1.27 1.27)
					(thickness 0.15)
				)
				(justify left bottom)
				(hide yes)
			)
		)
		(property "License" "Apache-2.0"
			(at 106.68 209.55 0)
			(effects
				(font
					(size 1.27 1.27)
					(thickness 0.15)
				)
				(justify left bottom)
				(hide yes)
			)
		)
		(property "VSD_class" "LED"
			(at 104.14 209.55 0)
			(effects
				(font
					(size 1.27 1.27)
				)
				(justify left bottom)
				(hide yes)
			)
		)
		(property "Color" "Green"
			(at 124.46 209.55 0)
			(effects
				(font
					(size 1.27 1.27)
				)
				(justify left bottom)
				(hide yes)
			)
		)
		(pin "1"
		)
		(pin "2"
		)
		(instances
			(project "gmsl-deserializer"
				(path ""
					(reference "D17")
					(unit 1)
				)
			)
		)
	)
	(symbol
		(lib_id "antmicroTestPoints:TP_0.75mm_SMD")
		(at 67.31 223.52 90)
		(unit 1)
		(exclude_from_sim no)
		(in_bom yes)
		(on_board yes)
		(dnp no)
		(property "Reference" "TP21"
			(at 66.04 218.44 90)
			(effects
				(font
					(size 1.27 1.27)
					(thickness 0.15)
				)
				(justify right)
			)
		)
		(property "Value" "TP_0.75mm_SMD"
			(at 71.12 212.725 0)
			(effects
				(font
					(size 1.27 1.27)
					(thickness 0.15)
				)
				(justify left bottom)
				(hide yes)
			)
		)
		(property "Footprint" "antmicro-footprints:TP_SMD_0.75mm"
			(at 73.66 212.725 0)
			(effects
				(font
					(size 1.27 1.27)
					(thickness 0.15)
				)
				(justify left bottom)
				(hide yes)
			)
		)
		(property "Datasheet" ""
			(at 80.01 205.74 0)
			(effects
				(font
					(size 1.27 1.27)
					(thickness 0.15)
				)
				(justify left bottom)
				(hide yes)
			)
		)
		(property "Description" "SMT test point"
			(at 67.31 223.52 0)
			(effects
				(font
					(size 1.27 1.27)
				)
				(hide yes)
			)
		)
		(property "MPN" ""
			(at 78.74 212.725 0)
			(effects
				(font
					(size 1.27 1.27)
					(thickness 0.15)
				)
				(justify left bottom)
				(hide yes)
			)
		)
		(property "Manufacturer" ""
			(at 73.66 212.725 0)
			(effects
				(font
					(size 1.27 1.27)
					(thickness 0.15)
				)
				(justify left bottom)
				(hide yes)
			)
		)
		(property "Author" "Antmicro"
			(at 76.2 212.725 0)
			(effects
				(font
					(size 1.27 1.27)
					(thickness 0.15)
				)
				(justify left bottom)
				(hide yes)
			)
		)
		(property "License" "Apache-2.0"
			(at 78.74 212.725 0)
			(effects
				(font
					(size 1.27 1.27)
					(thickness 0.15)
				)
				(justify left bottom)
				(hide yes)
			)
		)
		(pin "1"
		)
		(instances
			(project "gmsl-deserializer"
				(path ""
					(reference "TP21")
					(unit 1)
				)
			)
		)
	)
	(symbol
		(lib_id "antmicroDiodesRectifiersSingle:PMEG3010CEJ,115")
		(at 234.95 232.41 0)
		(mirror y)
		(unit 1)
		(exclude_from_sim no)
		(in_bom yes)
		(on_board yes)
		(dnp no)
		(fields_autoplaced yes)
		(property "Reference" "D3"
			(at 232.41 226.06 0)
			(effects
				(font
					(size 1.27 1.27)
					(thickness 0.15)
				)
			)
		)
		(property "Value" "PMEG3010CEJ,115"
			(at 212.09 247.65 0)
			(effects
				(font
					(size 1.27 1.27)
					(thickness 0.15)
				)
				(justify left bottom)
				(hide yes)
			)
		)
		(property "Footprint" "antmicro-footprints:D_SOD-323F"
			(at 212.09 242.57 0)
			(effects
				(font
					(size 1.27 1.27)
					(thickness 0.15)
				)
				(justify left bottom)
				(hide yes)
			)
		)
		(property "Datasheet" "https://assets.nexperia.com/documents/data-sheet/PMEG3010CEH_PMEG3010CEJ.pdf"
			(at 212.09 245.11 0)
			(effects
				(font
					(size 1.27 1.27)
					(thickness 0.15)
				)
				(justify left bottom)
				(hide yes)
			)
		)
		(property "Description" "Schottky Rectifier, 30 V, 1 A, Single, SOD-323F, 2 Pins, 520 mV"
			(at 234.95 232.41 0)
			(effects
				(font
					(size 1.27 1.27)
				)
				(hide yes)
			)
		)
		(property "MPN" "PMEG3010CEJ,115"
			(at 232.41 228.6 0)
			(effects
				(font
					(size 1.27 1.27)
					(thickness 0.15)
				)
			)
		)
		(property "Manufacturer" "Nexperia"
			(at 212.09 250.19 0)
			(effects
				(font
					(size 1.27 1.27)
					(thickness 0.15)
				)
				(justify left bottom)
				(hide yes)
			)
		)
		(property "Author" "Antmicro"
			(at 212.09 252.73 0)
			(effects
				(font
					(size 1.27 1.27)
					(thickness 0.15)
				)
				(justify left bottom)
				(hide yes)
			)
		)
		(property "Public" ""
			(at 214.63 250.19 0)
			(effects
				(font
					(size 1.27 1.27)
				)
				(justify left bottom)
				(hide yes)
			)
		)
		(property "License" "Apache-2.0"
			(at 212.09 255.27 0)
			(effects
				(font
					(size 1.27 1.27)
					(thickness 0.15)
				)
				(justify left bottom)
				(hide yes)
			)
		)
		(pin "1"
		)
		(pin "2"
		)
		(instances
			(project "gmsl-deserializer"
				(path ""
					(reference "D3")
					(unit 1)
				)
			)
		)
	)
	(symbol
		(lib_id "antmicroResistors0402:R_1k65_0402")
		(at 275.59 264.16 90)
		(unit 1)
		(exclude_from_sim no)
		(in_bom yes)
		(on_board yes)
		(dnp no)
		(fields_autoplaced yes)
		(property "Reference" "R78"
			(at 278.13 260.35 90)
			(effects
				(font
					(size 1.27 1.27)
					(thickness 0.15)
				)
				(justify right)
			)
		)
		(property "Value" "R_1k65_0402"
			(at 288.29 243.84 0)
			(effects
				(font
					(size 1.27 1.27)
					(thickness 0.15)
				)
				(justify left bottom)
				(hide yes)
			)
		)
		(property "Footprint" "antmicro-footprints:R_0402_1005Metric"
			(at 290.83 243.84 0)
			(effects
				(font
					(size 1.27 1.27)
					(thickness 0.15)
				)
				(justify left bottom)
				(hide yes)
			)
		)
		(property "Datasheet" "https://www.farnell.com/datasheets/3795017.pdf"
			(at 293.37 243.84 0)
			(effects
				(font
					(size 1.27 1.27)
					(thickness 0.15)
				)
				(justify left bottom)
				(hide yes)
			)
		)
		(property "Description" "SMD Chip Resistor, 1.65 kohm, ± 1%, 63 mW, 0402 [1005 Metric], Thick Film, General Purpose"
			(at 275.59 264.16 0)
			(effects
				(font
					(size 1.27 1.27)
				)
				(hide yes)
			)
		)
		(property "MPN" "RC0402FR-071K65L"
			(at 295.91 243.84 0)
			(effects
				(font
					(size 1.27 1.27)
					(thickness 0.15)
				)
				(justify left bottom)
				(hide yes)
			)
		)
		(property "Manufacturer" "YAGEO"
			(at 298.45 243.84 0)
			(effects
				(font
					(size 1.27 1.27)
					(thickness 0.15)
				)
				(justify left bottom)
				(hide yes)
			)
		)
		(property "License" "Apache-2.0"
			(at 300.99 243.84 0)
			(effects
				(font
					(size 1.27 1.27)
					(thickness 0.15)
				)
				(justify left bottom)
				(hide yes)
			)
		)
		(property "Author" "Antmicro"
			(at 303.53 243.84 0)
			(effects
				(font
					(size 1.27 1.27)
					(thickness 0.15)
				)
				(justify left bottom)
				(hide yes)
			)
		)
		(property "Val" "1k65"
			(at 278.13 262.89 90)
			(effects
				(font
					(size 1.27 1.27)
					(thickness 0.15)
				)
				(justify right)
			)
		)
		(property "Tolerance" "1%"
			(at 285.75 243.84 0)
			(effects
				(font
					(size 1.27 1.27)
				)
				(justify left bottom)
				(hide yes)
			)
		)
		(property "Public" ""
			(at 306.07 243.84 0)
			(effects
				(font
					(size 1.27 1.27)
				)
				(justify left bottom)
				(hide yes)
			)
		)
		(pin "1"
		)
		(pin "2"
		)
		(instances
			(project "gmsl-deserializer"
				(path ""
					(reference "R78")
					(unit 1)
				)
			)
		)
	)
	(symbol
		(lib_id "antmicroResistors0402:R_10k_0402")
		(at 50.8 252.73 90)
		(unit 1)
		(exclude_from_sim no)
		(in_bom yes)
		(on_board yes)
		(dnp no)
		(property "Reference" "R16"
			(at 52.705 248.92 90)
			(effects
				(font
					(size 1.27 1.27)
					(thickness 0.15)
				)
				(justify right)
			)
		)
		(property "Value" "R_10k_0402"
			(at 63.5 232.41 0)
			(effects
				(font
					(size 1.27 1.27)
					(thickness 0.15)
				)
				(justify left bottom)
				(hide yes)
			)
		)
		(property "Footprint" "antmicro-footprints:R_0402_1005Metric"
			(at 66.04 232.41 0)
			(effects
				(font
					(size 1.27 1.27)
					(thickness 0.15)
				)
				(justify left bottom)
				(hide yes)
			)
		)
		(property "Datasheet" "https://www.bourns.com/docs/product-datasheets/cr.pdf"
			(at 68.58 232.41 0)
			(effects
				(font
					(size 1.27 1.27)
					(thickness 0.15)
				)
				(justify left bottom)
				(hide yes)
			)
		)
		(property "Description" "SMD Chip Resistor, 10 kohm, ± 1%, 62.5 mW, 0402 [1005 Metric], Thick Film, General Purpose"
			(at 50.8 252.73 0)
			(effects
				(font
					(size 1.27 1.27)
				)
				(hide yes)
			)
		)
		(property "MPN" "CR0402-FX-1002GLF"
			(at 71.12 232.41 0)
			(effects
				(font
					(size 1.27 1.27)
					(thickness 0.15)
				)
				(justify left bottom)
				(hide yes)
			)
		)
		(property "Manufacturer" "Bourns"
			(at 73.66 232.41 0)
			(effects
				(font
					(size 1.27 1.27)
					(thickness 0.15)
				)
				(justify left bottom)
				(hide yes)
			)
		)
		(property "License" "Apache-2.0"
			(at 76.2 232.41 0)
			(effects
				(font
					(size 1.27 1.27)
					(thickness 0.15)
				)
				(justify left bottom)
				(hide yes)
			)
		)
		(property "Author" "Antmicro"
			(at 78.74 232.41 0)
			(effects
				(font
					(size 1.27 1.27)
					(thickness 0.15)
				)
				(justify left bottom)
				(hide yes)
			)
		)
		(property "Val" "10k"
			(at 52.705 251.4599 90)
			(effects
				(font
					(size 1.27 1.27)
					(thickness 0.15)
				)
				(justify right)
			)
		)
		(property "Tolerance" "1%"
			(at 60.96 232.41 0)
			(effects
				(font
					(size 1.27 1.27)
				)
				(justify left bottom)
				(hide yes)
			)
		)
		(pin "1"
		)
		(pin "2"
		)
		(instances
			(project "gmsl-deserializer"
				(path ""
					(reference "R16")
					(unit 1)
				)
			)
		)
	)
	(symbol
		(lib_id "antmicropower:+12V")
		(at 81.28 87.63 0)
		(unit 1)
		(exclude_from_sim no)
		(in_bom yes)
		(on_board yes)
		(dnp no)
		(fields_autoplaced yes)
		(property "Reference" "#PWR024"
			(at 81.28 91.44 0)
			(effects
				(font
					(size 1.27 1.27)
				)
				(hide yes)
			)
		)
		(property "Value" "+12V"
			(at 81.28 82.55 0)
			(effects
				(font
					(size 1.27 1.27)
				)
			)
		)
		(property "Footprint" ""
			(at 81.28 87.63 0)
			(effects
				(font
					(size 1.27 1.27)
				)
				(hide yes)
			)
		)
		(property "Datasheet" ""
			(at 81.28 87.63 0)
			(effects
				(font
					(size 1.27 1.27)
				)
				(hide yes)
			)
		)
		(property "Description" ""
			(at 81.28 87.63 0)
			(effects
				(font
					(size 1.27 1.27)
				)
				(hide yes)
			)
		)
		(pin "1"
		)
		(instances
			(project "gmsl-deserializer"
				(path ""
					(reference "#PWR024")
					(unit 1)
				)
			)
		)
	)
	(symbol
		(lib_id "antmicroTransistorsFETsMOSFETsSingle:BSS138AKA")
		(at 57.15 245.11 0)
		(unit 1)
		(exclude_from_sim no)
		(in_bom yes)
		(on_board yes)
		(dnp no)
		(fields_autoplaced yes)
		(property "Reference" "Q1"
			(at 66.675 241.2999 0)
			(effects
				(font
					(size 1.27 1.27)
					(thickness 0.15)
				)
				(justify left)
			)
		)
		(property "Value" "BSS138AKA"
			(at 72.39 252.73 0)
			(effects
				(font
					(size 1.27 1.27)
					(thickness 0.15)
				)
				(justify left bottom)
				(hide yes)
			)
		)
		(property "Footprint" "antmicro-footprints:SOT-23-3"
			(at 72.39 257.81 0)
			(effects
				(font
					(size 1.27 1.27)
					(thickness 0.15)
				)
				(justify left bottom)
				(hide yes)
			)
		)
		(property "Datasheet" "https://www.onsemi.com/pub/Collateral/BSS138-D.PDF"
			(at 72.39 260.35 0)
			(effects
				(font
					(size 1.27 1.27)
					(thickness 0.15)
				)
				(justify left bottom)
				(hide yes)
			)
		)
		(property "Description" "Power MOSFET, N Channel, 50 V, 220 mA, 6.0 ohm, SOT-23, Surface Mount"
			(at 57.15 245.11 0)
			(effects
				(font
					(size 1.27 1.27)
				)
				(hide yes)
			)
		)
		(property "MPN" "BSS138AKA"
			(at 66.675 243.8399 0)
			(effects
				(font
					(size 1.27 1.27)
					(thickness 0.15)
				)
				(justify left)
			)
		)
		(property "Manufacturer" "ON Semiconductor"
			(at 72.39 255.27 0)
			(effects
				(font
					(size 1.27 1.27)
					(thickness 0.15)
				)
				(justify left bottom)
				(hide yes)
			)
		)
		(property "Author" "Antmicro"
			(at 72.39 262.89 0)
			(effects
				(font
					(size 1.27 1.27)
					(thickness 0.15)
				)
				(justify left bottom)
				(hide yes)
			)
		)
		(property "License" "Apache-2.0"
			(at 72.39 265.43 0)
			(effects
				(font
					(size 1.27 1.27)
					(thickness 0.15)
				)
				(justify left bottom)
				(hide yes)
			)
		)
		(pin "1"
		)
		(pin "2"
		)
		(pin "3"
		)
		(instances
			(project "gmsl-deserializer"
				(path ""
					(reference "Q1")
					(unit 1)
				)
			)
		)
	)
	(symbol
		(lib_id "antmicroTestPoints:TP_0.75mm_SMD")
		(at 336.55 55.88 90)
		(unit 1)
		(exclude_from_sim no)
		(in_bom yes)
		(on_board yes)
		(dnp no)
		(property "Reference" "TP17"
			(at 335.28 50.8 90)
			(effects
				(font
					(size 1.27 1.27)
					(thickness 0.15)
				)
				(justify right)
			)
		)
		(property "Value" "TP_0.75mm_SMD"
			(at 340.36 45.085 0)
			(effects
				(font
					(size 1.27 1.27)
					(thickness 0.15)
				)
				(justify left bottom)
				(hide yes)
			)
		)
		(property "Footprint" "antmicro-footprints:TP_SMD_0.75mm"
			(at 342.9 45.085 0)
			(effects
				(font
					(size 1.27 1.27)
					(thickness 0.15)
				)
				(justify left bottom)
				(hide yes)
			)
		)
		(property "Datasheet" ""
			(at 349.25 38.1 0)
			(effects
				(font
					(size 1.27 1.27)
					(thickness 0.15)
				)
				(justify left bottom)
				(hide yes)
			)
		)
		(property "Description" "SMT test point"
			(at 336.55 55.88 0)
			(effects
				(font
					(size 1.27 1.27)
				)
				(hide yes)
			)
		)
		(property "MPN" ""
			(at 347.98 45.085 0)
			(effects
				(font
					(size 1.27 1.27)
					(thickness 0.15)
				)
				(justify left bottom)
				(hide yes)
			)
		)
		(property "Manufacturer" ""
			(at 342.9 45.085 0)
			(effects
				(font
					(size 1.27 1.27)
					(thickness 0.15)
				)
				(justify left bottom)
				(hide yes)
			)
		)
		(property "Author" "Antmicro"
			(at 345.44 45.085 0)
			(effects
				(font
					(size 1.27 1.27)
					(thickness 0.15)
				)
				(justify left bottom)
				(hide yes)
			)
		)
		(property "License" "Apache-2.0"
			(at 347.98 45.085 0)
			(effects
				(font
					(size 1.27 1.27)
					(thickness 0.15)
				)
				(justify left bottom)
				(hide yes)
			)
		)
		(pin "1"
		)
		(instances
			(project "gmsl-deserializer"
				(path ""
					(reference "TP17")
					(unit 1)
				)
			)
		)
	)
	(symbol
		(lib_id "antmicroResistors0402:R_470R_0402")
		(at 168.91 248.92 90)
		(unit 1)
		(exclude_from_sim no)
		(in_bom yes)
		(on_board yes)
		(dnp no)
		(fields_autoplaced yes)
		(property "Reference" "R77"
			(at 171.45 245.1099 90)
			(effects
				(font
					(size 1.27 1.27)
					(thickness 0.15)
				)
				(justify right)
			)
		)
		(property "Value" "R_470R_0402"
			(at 181.61 228.6 0)
			(effects
				(font
					(size 1.27 1.27)
					(thickness 0.15)
				)
				(justify left bottom)
				(hide yes)
			)
		)
		(property "Footprint" "antmicro-footprints:R_0402_1005Metric"
			(at 184.15 228.6 0)
			(effects
				(font
					(size 1.27 1.27)
					(thickness 0.15)
				)
				(justify left bottom)
				(hide yes)
			)
		)
		(property "Datasheet" "https://www.bourns.com/docs/product-datasheets/cr.pdf"
			(at 186.69 228.6 0)
			(effects
				(font
					(size 1.27 1.27)
					(thickness 0.15)
				)
				(justify left bottom)
				(hide yes)
			)
		)
		(property "Description" "SMD Chip Resistor, 470 ohm, ± 1%, 62.5 mW, 0402 [1005 Metric], Thick Film, General Purpose"
			(at 168.91 248.92 0)
			(effects
				(font
					(size 1.27 1.27)
				)
				(hide yes)
			)
		)
		(property "MPN" "CR0402-FX-4700GLF"
			(at 189.23 228.6 0)
			(effects
				(font
					(size 1.27 1.27)
					(thickness 0.15)
				)
				(justify left bottom)
				(hide yes)
			)
		)
		(property "Manufacturer" "Bourns"
			(at 191.77 228.6 0)
			(effects
				(font
					(size 1.27 1.27)
					(thickness 0.15)
				)
				(justify left bottom)
				(hide yes)
			)
		)
		(property "License" "Apache-2.0"
			(at 194.31 228.6 0)
			(effects
				(font
					(size 1.27 1.27)
					(thickness 0.15)
				)
				(justify left bottom)
				(hide yes)
			)
		)
		(property "Author" "Antmicro"
			(at 196.85 228.6 0)
			(effects
				(font
					(size 1.27 1.27)
					(thickness 0.15)
				)
				(justify left bottom)
				(hide yes)
			)
		)
		(property "Val" "470R"
			(at 171.45 247.6499 90)
			(effects
				(font
					(size 1.27 1.27)
					(thickness 0.15)
				)
				(justify right)
			)
		)
		(property "Tolerance" "1%"
			(at 179.07 228.6 0)
			(effects
				(font
					(size 1.27 1.27)
				)
				(justify left bottom)
				(hide yes)
			)
		)
		(pin "1"
		)
		(pin "2"
		)
		(instances
			(project "gmsl-deserializer"
				(path ""
					(reference "R77")
					(unit 1)
				)
			)
		)
	)
	(symbol
		(lib_id "antmicroResistors0402:R_5k1_0402")
		(at 104.14 72.39 0)
		(unit 1)
		(exclude_from_sim no)
		(in_bom yes)
		(on_board yes)
		(dnp no)
		(fields_autoplaced yes)
		(property "Reference" "R19"
			(at 106.68 66.675 0)
			(effects
				(font
					(size 1.27 1.27)
					(thickness 0.15)
				)
			)
		)
		(property "Value" "R_5k1_0402"
			(at 124.46 85.09 0)
			(effects
				(font
					(size 1.27 1.27)
					(thickness 0.15)
				)
				(justify left bottom)
				(hide yes)
			)
		)
		(property "Footprint" "antmicro-footprints:R_0402_1005Metric"
			(at 124.46 87.63 0)
			(effects
				(font
					(size 1.27 1.27)
					(thickness 0.15)
				)
				(justify left bottom)
				(hide yes)
			)
		)
		(property "Datasheet" "https://www.bourns.com/docs/product-datasheets/cr.pdf"
			(at 124.46 90.17 0)
			(effects
				(font
					(size 1.27 1.27)
					(thickness 0.15)
				)
				(justify left bottom)
				(hide yes)
			)
		)
		(property "Description" "SMD Chip Resistor, 5.1 kohm, ± 1%, 63 mW, 0402 [1005 Metric], Thick Film, General Purpose"
			(at 104.14 72.39 0)
			(effects
				(font
					(size 1.27 1.27)
				)
				(hide yes)
			)
		)
		(property "MPN" "CR0402-FX-5101GLF"
			(at 124.46 92.71 0)
			(effects
				(font
					(size 1.27 1.27)
					(thickness 0.15)
				)
				(justify left bottom)
				(hide yes)
			)
		)
		(property "Manufacturer" "Bourns"
			(at 124.46 95.25 0)
			(effects
				(font
					(size 1.27 1.27)
					(thickness 0.15)
				)
				(justify left bottom)
				(hide yes)
			)
		)
		(property "License" "Apache-2.0"
			(at 124.46 97.79 0)
			(effects
				(font
					(size 1.27 1.27)
					(thickness 0.15)
				)
				(justify left bottom)
				(hide yes)
			)
		)
		(property "Author" "Antmicro"
			(at 124.46 100.33 0)
			(effects
				(font
					(size 1.27 1.27)
					(thickness 0.15)
				)
				(justify left bottom)
				(hide yes)
			)
		)
		(property "Val" "5k1"
			(at 106.68 69.215 0)
			(effects
				(font
					(size 1.27 1.27)
					(thickness 0.15)
				)
			)
		)
		(property "Tolerance" "1%"
			(at 124.46 82.55 0)
			(effects
				(font
					(size 1.27 1.27)
				)
				(justify left bottom)
				(hide yes)
			)
		)
		(pin "1"
		)
		(pin "2"
		)
		(instances
			(project "gmsl-deserializer"
				(path ""
					(reference "R19")
					(unit 1)
				)
			)
		)
	)
	(symbol
		(lib_id "antmicroCapacitors0402:C_2u2_0402")
		(at 180.34 236.22 90)
		(unit 1)
		(exclude_from_sim no)
		(in_bom yes)
		(on_board yes)
		(dnp no)
		(property "Reference" "C14"
			(at 182.88 232.4035 90)
			(effects
				(font
					(size 1.27 1.27)
					(thickness 0.15)
				)
				(justify right)
			)
		)
		(property "Value" "C_2u2_0402"
			(at 190.5 215.9 0)
			(effects
				(font
					(size 1.27 1.27)
					(thickness 0.15)
				)
				(justify left bottom)
				(hide yes)
			)
		)
		(property "Footprint" "antmicro-footprints:C_0402_1005Metric"
			(at 193.04 215.9 0)
			(effects
				(font
					(size 1.27 1.27)
					(thickness 0.15)
				)
				(justify left bottom)
				(hide yes)
			)
		)
		(property "Datasheet" "https://product.tdk.com/en/search/capacitor/ceramic/mlcc/info?part_no=C1005X5R1A225K050BC"
			(at 195.58 215.9 0)
			(effects
				(font
					(size 1.27 1.27)
					(thickness 0.15)
				)
				(justify left bottom)
				(hide yes)
			)
		)
		(property "Description" "SMD Multilayer Ceramic Capacitor, 2.2 µF, 10 V, 0402 [1005 Metric], ± 10%, X5R, C"
			(at 180.34 236.22 0)
			(effects
				(font
					(size 1.27 1.27)
				)
				(hide yes)
			)
		)
		(property "MPN" "C1005X5R1A225K050BC"
			(at 198.12 215.9 0)
			(effects
				(font
					(size 1.27 1.27)
					(thickness 0.15)
				)
				(justify left bottom)
				(hide yes)
			)
		)
		(property "Manufacturer" "TDK"
			(at 200.66 215.9 0)
			(effects
				(font
					(size 1.27 1.27)
					(thickness 0.15)
				)
				(justify left bottom)
				(hide yes)
			)
		)
		(property "License" "Apache-2.0"
			(at 203.2 215.9 0)
			(effects
				(font
					(size 1.27 1.27)
					(thickness 0.15)
				)
				(justify left bottom)
				(hide yes)
			)
		)
		(property "Author" "Antmicro"
			(at 205.74 215.9 0)
			(effects
				(font
					(size 1.27 1.27)
					(thickness 0.15)
				)
				(justify left bottom)
				(hide yes)
			)
		)
		(property "Val" "2u2"
			(at 182.88 234.9435 90)
			(effects
				(font
					(size 1.27 1.27)
					(thickness 0.15)
				)
				(justify right)
			)
		)
		(property "Voltage" ""
			(at 208.28 215.9 0)
			(effects
				(font
					(size 1.27 1.27)
				)
				(justify left bottom)
				(hide yes)
			)
		)
		(property "Dielectric" ""
			(at 210.82 215.9 0)
			(effects
				(font
					(size 1.27 1.27)
				)
				(justify left bottom)
				(hide yes)
			)
		)
		(pin "1"
		)
		(pin "2"
		)
		(instances
			(project "gmsl-deserializer"
				(path ""
					(reference "C14")
					(unit 1)
				)
			)
		)
	)
	(symbol
		(lib_id "antmicroCapacitors0402:C_100n_0402")
		(at 311.15 137.16 0)
		(unit 1)
		(exclude_from_sim no)
		(in_bom yes)
		(on_board yes)
		(dnp no)
		(property "Reference" "C20"
			(at 316.23 135.89 0)
			(effects
				(font
					(size 1.27 1.27)
					(thickness 0.15)
				)
			)
		)
		(property "Value" "C_100n_0402"
			(at 331.47 147.32 0)
			(effects
				(font
					(size 1.27 1.27)
					(thickness 0.15)
				)
				(justify left bottom)
				(hide yes)
			)
		)
		(property "Footprint" "antmicro-footprints:C_0402_1005Metric"
			(at 331.47 149.86 0)
			(effects
				(font
					(size 1.27 1.27)
					(thickness 0.15)
				)
				(justify left bottom)
				(hide yes)
			)
		)
		(property "Datasheet" "https://www.murata.com/products/productdetail?partno=GRM155R61H104KE14%23"
			(at 331.47 152.4 0)
			(effects
				(font
					(size 1.27 1.27)
					(thickness 0.15)
				)
				(justify left bottom)
				(hide yes)
			)
		)
		(property "Description" "SMD Multilayer Ceramic Capacitor, 0.1 µF, 50 V, 0402 [1005 Metric], ± 10%, X5R, GRM Series"
			(at 311.15 137.16 0)
			(effects
				(font
					(size 1.27 1.27)
				)
				(hide yes)
			)
		)
		(property "MPN" "GRM155R61H104KE14D"
			(at 331.47 154.94 0)
			(effects
				(font
					(size 1.27 1.27)
					(thickness 0.15)
				)
				(justify left bottom)
				(hide yes)
			)
		)
		(property "Manufacturer" "Murata"
			(at 331.47 157.48 0)
			(effects
				(font
					(size 1.27 1.27)
					(thickness 0.15)
				)
				(justify left bottom)
				(hide yes)
			)
		)
		(property "License" "Apache-2.0"
			(at 331.47 160.02 0)
			(effects
				(font
					(size 1.27 1.27)
					(thickness 0.15)
				)
				(justify left bottom)
				(hide yes)
			)
		)
		(property "Author" "Antmicro"
			(at 331.47 162.56 0)
			(effects
				(font
					(size 1.27 1.27)
					(thickness 0.15)
				)
				(justify left bottom)
				(hide yes)
			)
		)
		(property "Val" "100n"
			(at 317.5 138.43 0)
			(effects
				(font
					(size 1.27 1.27)
					(thickness 0.15)
				)
			)
		)
		(property "Voltage" "50V"
			(at 331.47 165.1 0)
			(effects
				(font
					(size 1.27 1.27)
				)
				(justify left bottom)
				(hide yes)
			)
		)
		(property "Dielectric" "X5R"
			(at 331.47 167.64 0)
			(effects
				(font
					(size 1.27 1.27)
				)
				(justify left bottom)
				(hide yes)
			)
		)
		(pin "1"
		)
		(pin "2"
		)
		(instances
			(project "gmsl-deserializer"
				(path ""
					(reference "C20")
					(unit 1)
				)
			)
		)
	)
	(symbol
		(lib_id "antmicropower:GND")
		(at 180.34 237.49 0)
		(unit 1)
		(exclude_from_sim no)
		(in_bom yes)
		(on_board yes)
		(dnp no)
		(property "Reference" "#PWR037"
			(at 189.23 240.03 0)
			(effects
				(font
					(size 1.27 1.27)
					(thickness 0.15)
				)
				(justify left bottom)
				(hide yes)
			)
		)
		(property "Value" "GND"
			(at 180.34 241.3 0)
			(effects
				(font
					(size 1.27 1.27)
					(thickness 0.15)
				)
			)
		)
		(property "Footprint" ""
			(at 189.23 245.11 0)
			(effects
				(font
					(size 1.27 1.27)
					(thickness 0.15)
				)
				(justify left bottom)
				(hide yes)
			)
		)
		(property "Datasheet" ""
			(at 189.23 250.19 0)
			(effects
				(font
					(size 1.27 1.27)
					(thickness 0.15)
				)
				(justify left bottom)
				(hide yes)
			)
		)
		(property "Description" ""
			(at 180.34 237.49 0)
			(effects
				(font
					(size 1.27 1.27)
				)
				(hide yes)
			)
		)
		(property "Author" "Antmicro"
			(at 189.23 245.11 0)
			(effects
				(font
					(size 1.27 1.27)
					(thickness 0.15)
				)
				(justify left bottom)
				(hide yes)
			)
		)
		(property "License" "Apache-2.0"
			(at 189.23 247.65 0)
			(effects
				(font
					(size 1.27 1.27)
					(thickness 0.15)
				)
				(justify left bottom)
				(hide yes)
			)
		)
		(pin "1"
		)
		(instances
			(project "gmsl-deserializer"
				(path ""
					(reference "#PWR037")
					(unit 1)
				)
			)
		)
	)
	(symbol
		(lib_id "antmicropower:+1V2")
		(at 377.19 130.81 0)
		(unit 1)
		(exclude_from_sim no)
		(in_bom yes)
		(on_board yes)
		(dnp no)
		(property "Reference" "#PWR061"
			(at 377.19 134.62 0)
			(effects
				(font
					(size 1.27 1.27)
				)
				(hide yes)
			)
		)
		(property "Value" "+1V2"
			(at 376.555 127 0)
			(effects
				(font
					(size 1.27 1.27)
				)
			)
		)
		(property "Footprint" ""
			(at 377.19 130.81 0)
			(effects
				(font
					(size 1.27 1.27)
				)
				(hide yes)
			)
		)
		(property "Datasheet" ""
			(at 377.19 130.81 0)
			(effects
				(font
					(size 1.27 1.27)
				)
				(hide yes)
			)
		)
		(property "Description" ""
			(at 377.19 130.81 0)
			(effects
				(font
					(size 1.27 1.27)
				)
				(hide yes)
			)
		)
		(pin "1"
		)
		(instances
			(project "gmsl-deserializer"
				(path ""
					(reference "#PWR061")
					(unit 1)
				)
			)
		)
	)
	(symbol
		(lib_id "antmicroCapacitors0402:C_22u_0402")
		(at 340.36 149.86 90)
		(unit 1)
		(exclude_from_sim no)
		(in_bom yes)
		(on_board yes)
		(dnp no)
		(fields_autoplaced yes)
		(property "Reference" "C22"
			(at 343.535 146.0435 90)
			(effects
				(font
					(size 1.27 1.27)
					(thickness 0.15)
				)
				(justify right)
			)
		)
		(property "Value" "C_22u_0402"
			(at 350.52 129.54 0)
			(effects
				(font
					(size 1.27 1.27)
					(thickness 0.15)
				)
				(justify left bottom)
				(hide yes)
			)
		)
		(property "Footprint" "antmicro-footprints:C_0402_1005Metric"
			(at 353.06 129.54 0)
			(effects
				(font
					(size 1.27 1.27)
					(thickness 0.15)
				)
				(justify left bottom)
				(hide yes)
			)
		)
		(property "Datasheet" "https://www.murata.com/products/productdetail?partno=GRM158R60J226ME01%23"
			(at 355.6 129.54 0)
			(effects
				(font
					(size 1.27 1.27)
					(thickness 0.15)
				)
				(justify left bottom)
				(hide yes)
			)
		)
		(property "Description" "SMD Multilayer Ceramic Capacitor, 22 uF, 4 V, 0402 [1005 Metric], X6S"
			(at 340.36 149.86 0)
			(effects
				(font
					(size 1.27 1.27)
				)
				(hide yes)
			)
		)
		(property "MPN" "GRM158R60J226ME01D"
			(at 358.14 129.54 0)
			(effects
				(font
					(size 1.27 1.27)
					(thickness 0.15)
				)
				(justify left bottom)
				(hide yes)
			)
		)
		(property "Manufacturer" "Murata"
			(at 360.68 129.54 0)
			(effects
				(font
					(size 1.27 1.27)
					(thickness 0.15)
				)
				(justify left bottom)
				(hide yes)
			)
		)
		(property "License" "Apache-2.0"
			(at 363.22 129.54 0)
			(effects
				(font
					(size 1.27 1.27)
					(thickness 0.15)
				)
				(justify left bottom)
				(hide yes)
			)
		)
		(property "Author" "Antmicro"
			(at 365.76 129.54 0)
			(effects
				(font
					(size 1.27 1.27)
					(thickness 0.15)
				)
				(justify left bottom)
				(hide yes)
			)
		)
		(property "Val" "22u"
			(at 343.535 148.5835 90)
			(effects
				(font
					(size 1.27 1.27)
					(thickness 0.15)
				)
				(justify right)
			)
		)
		(property "Voltage" ""
			(at 368.3 129.54 0)
			(effects
				(font
					(size 1.27 1.27)
				)
				(justify left bottom)
				(hide yes)
			)
		)
		(property "Dielectric" ""
			(at 370.84 129.54 0)
			(effects
				(font
					(size 1.27 1.27)
				)
				(justify left bottom)
				(hide yes)
			)
		)
		(pin "1"
		)
		(pin "2"
		)
		(instances
			(project "gmsl-deserializer"
				(path ""
					(reference "C22")
					(unit 1)
				)
			)
		)
	)
	(symbol
		(lib_id "antmicropower:GND")
		(at 217.17 251.46 0)
		(unit 1)
		(exclude_from_sim no)
		(in_bom yes)
		(on_board yes)
		(dnp no)
		(property "Reference" "#PWR039"
			(at 226.06 254 0)
			(effects
				(font
					(size 1.27 1.27)
					(thickness 0.15)
				)
				(justify left bottom)
				(hide yes)
			)
		)
		(property "Value" "GND"
			(at 217.17 255.27 0)
			(effects
				(font
					(size 1.27 1.27)
					(thickness 0.15)
				)
			)
		)
		(property "Footprint" ""
			(at 226.06 259.08 0)
			(effects
				(font
					(size 1.27 1.27)
					(thickness 0.15)
				)
				(justify left bottom)
				(hide yes)
			)
		)
		(property "Datasheet" ""
			(at 226.06 264.16 0)
			(effects
				(font
					(size 1.27 1.27)
					(thickness 0.15)
				)
				(justify left bottom)
				(hide yes)
			)
		)
		(property "Description" ""
			(at 217.17 251.46 0)
			(effects
				(font
					(size 1.27 1.27)
				)
				(hide yes)
			)
		)
		(property "Author" "Antmicro"
			(at 226.06 259.08 0)
			(effects
				(font
					(size 1.27 1.27)
					(thickness 0.15)
				)
				(justify left bottom)
				(hide yes)
			)
		)
		(property "License" "Apache-2.0"
			(at 226.06 261.62 0)
			(effects
				(font
					(size 1.27 1.27)
					(thickness 0.15)
				)
				(justify left bottom)
				(hide yes)
			)
		)
		(pin "1"
		)
		(instances
			(project "gmsl-deserializer"
				(path ""
					(reference "#PWR039")
					(unit 1)
				)
			)
		)
	)
	(symbol
		(lib_id "antmicroFixedInductors:L_6u8_1A_Coilcraft-1210POC")
		(at 121.92 88.9 0)
		(unit 1)
		(exclude_from_sim no)
		(in_bom yes)
		(on_board yes)
		(dnp no)
		(property "Reference" "L6"
			(at 124.46 83.82 0)
			(effects
				(font
					(size 1.27 1.27)
					(thickness 0.15)
				)
			)
		)
		(property "Value" "L_6u8_1A_Coilcraft-1210POC"
			(at 135.89 91.44 0)
			(effects
				(font
					(size 1.27 1.27)
					(thickness 0.15)
				)
				(justify left bottom)
				(hide yes)
			)
		)
		(property "Footprint" "antmicro-footprints:L_Coilcraft-1210POC"
			(at 135.89 96.52 0)
			(effects
				(font
					(size 1.27 1.27)
					(thickness 0.15)
				)
				(justify left bottom)
				(hide yes)
			)
		)
		(property "Datasheet" "https://www.coilcraft.com/getmedia/5e8de018-68c5-4442-84ce-d5212c44660c/1210poc.pdf"
			(at 135.89 99.06 0)
			(effects
				(font
					(size 1.27 1.27)
					(thickness 0.15)
				)
				(justify left bottom)
				(hide yes)
			)
		)
		(property "Description" "Power Inductor (SMT), 6.8 µH, 9.2 A, Shielded, 12.8 A, XAL7070"
			(at 121.92 88.9 0)
			(effects
				(font
					(size 1.27 1.27)
				)
				(hide yes)
			)
		)
		(property "Val" "6u8/1A"
			(at 124.46 86.36 0)
			(effects
				(font
					(size 1.27 1.27)
					(thickness 0.15)
				)
			)
		)
		(property "Manufacturer" "Coilcraft"
			(at 135.89 101.6 0)
			(effects
				(font
					(size 1.27 1.27)
					(thickness 0.15)
				)
				(justify left bottom)
				(hide yes)
			)
		)
		(property "MPN" "1210POC-682"
			(at 135.89 104.14 0)
			(effects
				(font
					(size 1.27 1.27)
					(thickness 0.15)
				)
				(justify left bottom)
				(hide yes)
			)
		)
		(property "ISat" "1 A"
			(at 135.89 105.41 0)
			(effects
				(font
					(size 1.27 1.27)
				)
				(justify left)
				(hide yes)
			)
		)
		(property "IMax" "1.36 A"
			(at 135.89 109.22 0)
			(effects
				(font
					(size 1.27 1.27)
					(thickness 0.15)
				)
				(justify left bottom)
				(hide yes)
			)
		)
		(property "Size" "2.67x3.3"
			(at 135.89 111.76 0)
			(effects
				(font
					(size 1.27 1.27)
					(thickness 0.15)
				)
				(justify left bottom)
				(hide yes)
			)
		)
		(property "Author" "Antmicro"
			(at 135.89 114.3 0)
			(effects
				(font
					(size 1.27 1.27)
					(thickness 0.15)
				)
				(justify left bottom)
				(hide yes)
			)
		)
		(property "License" "Apache-2.0"
			(at 135.89 116.84 0)
			(effects
				(font
					(size 1.27 1.27)
					(thickness 0.15)
				)
				(justify left bottom)
				(hide yes)
			)
		)
		(pin "1"
		)
		(pin "2"
		)
		(instances
			(project "gmsl-deserializer"
				(path ""
					(reference "L6")
					(unit 1)
				)
			)
		)
	)
	(symbol
		(lib_id "antmicropower:GND")
		(at 287.02 144.78 0)
		(unit 1)
		(exclude_from_sim no)
		(in_bom yes)
		(on_board yes)
		(dnp no)
		(property "Reference" "#PWR049"
			(at 295.91 147.32 0)
			(effects
				(font
					(size 1.27 1.27)
					(thickness 0.15)
				)
				(justify left bottom)
				(hide yes)
			)
		)
		(property "Value" "GND"
			(at 287.02 148.59 0)
			(effects
				(font
					(size 1.27 1.27)
					(thickness 0.15)
				)
			)
		)
		(property "Footprint" ""
			(at 295.91 152.4 0)
			(effects
				(font
					(size 1.27 1.27)
					(thickness 0.15)
				)
				(justify left bottom)
				(hide yes)
			)
		)
		(property "Datasheet" ""
			(at 295.91 157.48 0)
			(effects
				(font
					(size 1.27 1.27)
					(thickness 0.15)
				)
				(justify left bottom)
				(hide yes)
			)
		)
		(property "Description" ""
			(at 287.02 144.78 0)
			(effects
				(font
					(size 1.27 1.27)
				)
				(hide yes)
			)
		)
		(property "Author" "Antmicro"
			(at 295.91 152.4 0)
			(effects
				(font
					(size 1.27 1.27)
					(thickness 0.15)
				)
				(justify left bottom)
				(hide yes)
			)
		)
		(property "License" "Apache-2.0"
			(at 295.91 154.94 0)
			(effects
				(font
					(size 1.27 1.27)
					(thickness 0.15)
				)
				(justify left bottom)
				(hide yes)
			)
		)
		(pin "1"
		)
		(instances
			(project "gmsl-deserializer"
				(path ""
					(reference "#PWR049")
					(unit 1)
				)
			)
		)
	)
	(symbol
		(lib_id "antmicropower:+12V")
		(at 81.28 139.7 0)
		(unit 1)
		(exclude_from_sim no)
		(in_bom yes)
		(on_board yes)
		(dnp no)
		(fields_autoplaced yes)
		(property "Reference" "#PWR028"
			(at 81.28 143.51 0)
			(effects
				(font
					(size 1.27 1.27)
				)
				(hide yes)
			)
		)
		(property "Value" "+12V"
			(at 81.28 134.62 0)
			(effects
				(font
					(size 1.27 1.27)
				)
			)
		)
		(property "Footprint" ""
			(at 81.28 139.7 0)
			(effects
				(font
					(size 1.27 1.27)
				)
				(hide yes)
			)
		)
		(property "Datasheet" ""
			(at 81.28 139.7 0)
			(effects
				(font
					(size 1.27 1.27)
				)
				(hide yes)
			)
		)
		(property "Description" ""
			(at 81.28 139.7 0)
			(effects
				(font
					(size 1.27 1.27)
				)
				(hide yes)
			)
		)
		(pin "1"
		)
		(instances
			(project "gmsl-deserializer"
				(path ""
					(reference "#PWR028")
					(unit 1)
				)
			)
		)
	)
	(symbol
		(lib_id "antmicroTestPoints:TP_0.75mm_SMD")
		(at 337.82 130.81 90)
		(unit 1)
		(exclude_from_sim no)
		(in_bom yes)
		(on_board yes)
		(dnp no)
		(property "Reference" "TP16"
			(at 336.55 125.73 90)
			(effects
				(font
					(size 1.27 1.27)
					(thickness 0.15)
				)
				(justify right)
			)
		)
		(property "Value" "TP_0.75mm_SMD"
			(at 341.63 120.015 0)
			(effects
				(font
					(size 1.27 1.27)
					(thickness 0.15)
				)
				(justify left bottom)
				(hide yes)
			)
		)
		(property "Footprint" "antmicro-footprints:TP_SMD_0.75mm"
			(at 344.17 120.015 0)
			(effects
				(font
					(size 1.27 1.27)
					(thickness 0.15)
				)
				(justify left bottom)
				(hide yes)
			)
		)
		(property "Datasheet" ""
			(at 350.52 113.03 0)
			(effects
				(font
					(size 1.27 1.27)
					(thickness 0.15)
				)
				(justify left bottom)
				(hide yes)
			)
		)
		(property "Description" "SMT test point"
			(at 337.82 130.81 0)
			(effects
				(font
					(size 1.27 1.27)
				)
				(hide yes)
			)
		)
		(property "MPN" ""
			(at 349.25 120.015 0)
			(effects
				(font
					(size 1.27 1.27)
					(thickness 0.15)
				)
				(justify left bottom)
				(hide yes)
			)
		)
		(property "Manufacturer" ""
			(at 344.17 120.015 0)
			(effects
				(font
					(size 1.27 1.27)
					(thickness 0.15)
				)
				(justify left bottom)
				(hide yes)
			)
		)
		(property "Author" "Antmicro"
			(at 346.71 120.015 0)
			(effects
				(font
					(size 1.27 1.27)
					(thickness 0.15)
				)
				(justify left bottom)
				(hide yes)
			)
		)
		(property "License" "Apache-2.0"
			(at 349.25 120.015 0)
			(effects
				(font
					(size 1.27 1.27)
					(thickness 0.15)
				)
				(justify left bottom)
				(hide yes)
			)
		)
		(pin "1"
		)
		(instances
			(project "gmsl-deserializer"
				(path ""
					(reference "TP16")
					(unit 1)
				)
			)
		)
	)
	(symbol
		(lib_id "antmicroFixedInductors:L_6u8_1A_Coilcraft-1210POC")
		(at 121.92 62.23 0)
		(unit 1)
		(exclude_from_sim no)
		(in_bom yes)
		(on_board yes)
		(dnp no)
		(property "Reference" "L5"
			(at 124.46 57.15 0)
			(effects
				(font
					(size 1.27 1.27)
					(thickness 0.15)
				)
			)
		)
		(property "Value" "L_6u8_1A_Coilcraft-1210POC"
			(at 135.89 64.77 0)
			(effects
				(font
					(size 1.27 1.27)
					(thickness 0.15)
				)
				(justify left bottom)
				(hide yes)
			)
		)
		(property "Footprint" "antmicro-footprints:L_Coilcraft-1210POC"
			(at 135.89 69.85 0)
			(effects
				(font
					(size 1.27 1.27)
					(thickness 0.15)
				)
				(justify left bottom)
				(hide yes)
			)
		)
		(property "Datasheet" "https://www.coilcraft.com/getmedia/5e8de018-68c5-4442-84ce-d5212c44660c/1210poc.pdf"
			(at 135.89 72.39 0)
			(effects
				(font
					(size 1.27 1.27)
					(thickness 0.15)
				)
				(justify left bottom)
				(hide yes)
			)
		)
		(property "Description" "Power Inductor (SMT), 6.8 µH, 9.2 A, Shielded, 12.8 A, XAL7070"
			(at 121.92 62.23 0)
			(effects
				(font
					(size 1.27 1.27)
				)
				(hide yes)
			)
		)
		(property "Val" "6u8/1A"
			(at 124.46 59.69 0)
			(effects
				(font
					(size 1.27 1.27)
					(thickness 0.15)
				)
			)
		)
		(property "Manufacturer" "Coilcraft"
			(at 135.89 74.93 0)
			(effects
				(font
					(size 1.27 1.27)
					(thickness 0.15)
				)
				(justify left bottom)
				(hide yes)
			)
		)
		(property "MPN" "1210POC-682"
			(at 135.89 77.47 0)
			(effects
				(font
					(size 1.27 1.27)
					(thickness 0.15)
				)
				(justify left bottom)
				(hide yes)
			)
		)
		(property "ISat" "1 A"
			(at 135.89 78.74 0)
			(effects
				(font
					(size 1.27 1.27)
				)
				(justify left)
				(hide yes)
			)
		)
		(property "IMax" "1.36 A"
			(at 135.89 82.55 0)
			(effects
				(font
					(size 1.27 1.27)
					(thickness 0.15)
				)
				(justify left bottom)
				(hide yes)
			)
		)
		(property "Size" "2.67x3.3"
			(at 135.89 85.09 0)
			(effects
				(font
					(size 1.27 1.27)
					(thickness 0.15)
				)
				(justify left bottom)
				(hide yes)
			)
		)
		(property "Author" "Antmicro"
			(at 135.89 87.63 0)
			(effects
				(font
					(size 1.27 1.27)
					(thickness 0.15)
				)
				(justify left bottom)
				(hide yes)
			)
		)
		(property "License" "Apache-2.0"
			(at 135.89 90.17 0)
			(effects
				(font
					(size 1.27 1.27)
					(thickness 0.15)
				)
				(justify left bottom)
				(hide yes)
			)
		)
		(pin "1"
		)
		(pin "2"
		)
		(instances
			(project "gmsl-deserializer"
				(path ""
					(reference "L5")
					(unit 1)
				)
			)
		)
	)
	(symbol
		(lib_id "antmicroResistors0402:R_10k_0402")
		(at 309.88 222.25 90)
		(unit 1)
		(exclude_from_sim no)
		(in_bom yes)
		(on_board yes)
		(dnp no)
		(fields_autoplaced yes)
		(property "Reference" "R33"
			(at 311.785 218.4399 90)
			(effects
				(font
					(size 1.27 1.27)
					(thickness 0.15)
				)
				(justify right)
			)
		)
		(property "Value" "R_10k_0402"
			(at 322.58 201.93 0)
			(effects
				(font
					(size 1.27 1.27)
					(thickness 0.15)
				)
				(justify left bottom)
				(hide yes)
			)
		)
		(property "Footprint" "antmicro-footprints:R_0402_1005Metric"
			(at 325.12 201.93 0)
			(effects
				(font
					(size 1.27 1.27)
					(thickness 0.15)
				)
				(justify left bottom)
				(hide yes)
			)
		)
		(property "Datasheet" "https://www.bourns.com/docs/product-datasheets/cr.pdf"
			(at 327.66 201.93 0)
			(effects
				(font
					(size 1.27 1.27)
					(thickness 0.15)
				)
				(justify left bottom)
				(hide yes)
			)
		)
		(property "Description" "SMD Chip Resistor, 10 kohm, ± 1%, 62.5 mW, 0402 [1005 Metric], Thick Film, General Purpose"
			(at 309.88 222.25 0)
			(effects
				(font
					(size 1.27 1.27)
				)
				(hide yes)
			)
		)
		(property "MPN" "CR0402-FX-1002GLF"
			(at 330.2 201.93 0)
			(effects
				(font
					(size 1.27 1.27)
					(thickness 0.15)
				)
				(justify left bottom)
				(hide yes)
			)
		)
		(property "Manufacturer" "Bourns"
			(at 332.74 201.93 0)
			(effects
				(font
					(size 1.27 1.27)
					(thickness 0.15)
				)
				(justify left bottom)
				(hide yes)
			)
		)
		(property "License" "Apache-2.0"
			(at 335.28 201.93 0)
			(effects
				(font
					(size 1.27 1.27)
					(thickness 0.15)
				)
				(justify left bottom)
				(hide yes)
			)
		)
		(property "Author" "Antmicro"
			(at 337.82 201.93 0)
			(effects
				(font
					(size 1.27 1.27)
					(thickness 0.15)
				)
				(justify left bottom)
				(hide yes)
			)
		)
		(property "Val" "10k"
			(at 311.785 220.9799 90)
			(effects
				(font
					(size 1.27 1.27)
					(thickness 0.15)
				)
				(justify right)
			)
		)
		(property "Tolerance" "1%"
			(at 320.04 201.93 0)
			(effects
				(font
					(size 1.27 1.27)
				)
				(justify left bottom)
				(hide yes)
			)
		)
		(pin "1"
		)
		(pin "2"
		)
		(instances
			(project "gmsl-deserializer"
				(path ""
					(reference "R33")
					(unit 1)
				)
			)
		)
	)
	(symbol
		(lib_id "antmicroResistors0402:R_100R_0402")
		(at 50.8 242.57 90)
		(unit 1)
		(exclude_from_sim no)
		(in_bom yes)
		(on_board yes)
		(dnp no)
		(fields_autoplaced yes)
		(property "Reference" "R15"
			(at 52.705 238.7599 90)
			(effects
				(font
					(size 1.27 1.27)
					(thickness 0.15)
				)
				(justify right)
			)
		)
		(property "Value" "R_100R_0402"
			(at 63.5 222.25 0)
			(effects
				(font
					(size 1.27 1.27)
					(thickness 0.15)
				)
				(justify left bottom)
				(hide yes)
			)
		)
		(property "Footprint" "antmicro-footprints:R_0402_1005Metric"
			(at 66.04 222.25 0)
			(effects
				(font
					(size 1.27 1.27)
					(thickness 0.15)
				)
				(justify left bottom)
				(hide yes)
			)
		)
		(property "Datasheet" "https://www.bourns.com/docs/product-datasheets/cr.pdf"
			(at 68.58 222.25 0)
			(effects
				(font
					(size 1.27 1.27)
					(thickness 0.15)
				)
				(justify left bottom)
				(hide yes)
			)
		)
		(property "Description" "SMD Chip Resistor, 100 ohm, ± 1%, 62.5 mW, 0402 [1005 Metric], Thick Film, General Purpose"
			(at 50.8 242.57 0)
			(effects
				(font
					(size 1.27 1.27)
				)
				(hide yes)
			)
		)
		(property "MPN" "CR0402-FX-1000GLF"
			(at 71.12 222.25 0)
			(effects
				(font
					(size 1.27 1.27)
					(thickness 0.15)
				)
				(justify left bottom)
				(hide yes)
			)
		)
		(property "Manufacturer" "Bourns"
			(at 73.66 222.25 0)
			(effects
				(font
					(size 1.27 1.27)
					(thickness 0.15)
				)
				(justify left bottom)
				(hide yes)
			)
		)
		(property "License" "Apache-2.0"
			(at 76.2 222.25 0)
			(effects
				(font
					(size 1.27 1.27)
					(thickness 0.15)
				)
				(justify left bottom)
				(hide yes)
			)
		)
		(property "Author" "Antmicro"
			(at 78.74 222.25 0)
			(effects
				(font
					(size 1.27 1.27)
					(thickness 0.15)
				)
				(justify left bottom)
				(hide yes)
			)
		)
		(property "Val" "100R"
			(at 52.705 241.2999 90)
			(effects
				(font
					(size 1.27 1.27)
					(thickness 0.15)
				)
				(justify right)
			)
		)
		(property "Tolerance" "1%"
			(at 60.96 222.25 0)
			(effects
				(font
					(size 1.27 1.27)
				)
				(justify left bottom)
				(hide yes)
			)
		)
		(pin "1"
		)
		(pin "2"
		)
		(instances
			(project "gmsl-deserializer"
				(path ""
					(reference "R15")
					(unit 1)
				)
			)
		)
	)
	(symbol
		(lib_id "antmicropower:GND")
		(at 129.54 241.3 0)
		(unit 1)
		(exclude_from_sim no)
		(in_bom yes)
		(on_board yes)
		(dnp no)
		(property "Reference" "#PWR0119"
			(at 138.43 243.84 0)
			(effects
				(font
					(size 1.27 1.27)
					(thickness 0.15)
				)
				(justify left bottom)
				(hide yes)
			)
		)
		(property "Value" "GND"
			(at 129.54 245.11 0)
			(effects
				(font
					(size 1.27 1.27)
					(thickness 0.15)
				)
			)
		)
		(property "Footprint" ""
			(at 138.43 248.92 0)
			(effects
				(font
					(size 1.27 1.27)
					(thickness 0.15)
				)
				(justify left bottom)
				(hide yes)
			)
		)
		(property "Datasheet" ""
			(at 138.43 254 0)
			(effects
				(font
					(size 1.27 1.27)
					(thickness 0.15)
				)
				(justify left bottom)
				(hide yes)
			)
		)
		(property "Description" ""
			(at 129.54 241.3 0)
			(effects
				(font
					(size 1.27 1.27)
				)
				(hide yes)
			)
		)
		(property "Author" "Antmicro"
			(at 138.43 248.92 0)
			(effects
				(font
					(size 1.27 1.27)
					(thickness 0.15)
				)
				(justify left bottom)
				(hide yes)
			)
		)
		(property "License" "Apache-2.0"
			(at 138.43 251.46 0)
			(effects
				(font
					(size 1.27 1.27)
					(thickness 0.15)
				)
				(justify left bottom)
				(hide yes)
			)
		)
		(pin "1"
		)
		(instances
			(project "gmsl-deserializer"
				(path ""
					(reference "#PWR0119")
					(unit 1)
				)
			)
		)
	)
	(symbol
		(lib_id "antmicroResistors0603:R_0R_22.4A_0603")
		(at 353.06 55.88 0)
		(unit 1)
		(exclude_from_sim no)
		(in_bom yes)
		(on_board yes)
		(dnp no)
		(property "Reference" "R40"
			(at 355.6 50.8 0)
			(effects
				(font
					(size 1.27 1.27)
					(thickness 0.15)
				)
			)
		)
		(property "Value" "R_0R_22.4A_0603"
			(at 355.6 50.165 0)
			(effects
				(font
					(size 1.27 1.27)
					(thickness 0.15)
				)
				(hide yes)
			)
		)
		(property "Footprint" "antmicro-footprints:R_0603_1608Metric"
			(at 368.3 66.04 0)
			(effects
				(font
					(size 1.27 1.27)
					(thickness 0.15)
				)
				(justify left bottom)
				(hide yes)
			)
		)
		(property "Datasheet" "https://fscdn.rohm.com/en/products/databook/datasheet/passive/resistor/chip_resistor/pmr-jpw-e.pdf"
			(at 368.3 68.58 0)
			(effects
				(font
					(size 1.27 1.27)
					(thickness 0.15)
				)
				(justify left bottom)
				(hide yes)
			)
		)
		(property "Description" "SMD Chip Resistor"
			(at 353.06 55.88 0)
			(effects
				(font
					(size 1.27 1.27)
				)
				(hide yes)
			)
		)
		(property "MPN" "PMR03EZPJ000"
			(at 368.3 71.12 0)
			(effects
				(font
					(size 1.27 1.27)
					(thickness 0.15)
				)
				(justify left bottom)
				(hide yes)
			)
		)
		(property "Manufacturer" "ROHM Semiconductor"
			(at 368.3 73.66 0)
			(effects
				(font
					(size 1.27 1.27)
					(thickness 0.15)
				)
				(justify left bottom)
				(hide yes)
			)
		)
		(property "Val" "0R"
			(at 355.6 53.34 0)
			(effects
				(font
					(size 1.27 1.27)
					(thickness 0.15)
				)
			)
		)
		(property "Max. Curr." "22.4A"
			(at 355.6 58.42 0)
			(effects
				(font
					(size 1.27 1.27)
					(thickness 0.15)
				)
			)
		)
		(property "Author" "Antmicro"
			(at 368.3 78.74 0)
			(effects
				(font
					(size 1.27 1.27)
					(thickness 0.15)
				)
				(justify left bottom)
				(hide yes)
			)
		)
		(property "License" "Apache-2.0"
			(at 368.3 81.28 0)
			(effects
				(font
					(size 1.27 1.27)
					(thickness 0.15)
				)
				(justify left bottom)
				(hide yes)
			)
		)
		(property "Tolerance" "template_tolerance"
			(at 373.38 66.04 0)
			(effects
				(font
					(size 1.27 1.27)
				)
				(justify left bottom)
				(hide yes)
			)
		)
		(pin "1"
		)
		(pin "2"
		)
		(instances
			(project "gmsl-deserializer"
				(path ""
					(reference "R40")
					(unit 1)
				)
			)
		)
	)
	(symbol
		(lib_id "antmicroTestPoints:TP_0.75mm_SMD")
		(at 255.27 231.14 90)
		(unit 1)
		(exclude_from_sim no)
		(in_bom yes)
		(on_board yes)
		(dnp no)
		(property "Reference" "TP18"
			(at 254 226.06 90)
			(effects
				(font
					(size 1.27 1.27)
					(thickness 0.15)
				)
				(justify right)
			)
		)
		(property "Value" "TP_0.75mm_SMD"
			(at 259.08 220.345 0)
			(effects
				(font
					(size 1.27 1.27)
					(thickness 0.15)
				)
				(justify left bottom)
				(hide yes)
			)
		)
		(property "Footprint" "antmicro-footprints:TP_SMD_0.75mm"
			(at 261.62 220.345 0)
			(effects
				(font
					(size 1.27 1.27)
					(thickness 0.15)
				)
				(justify left bottom)
				(hide yes)
			)
		)
		(property "Datasheet" ""
			(at 267.97 213.36 0)
			(effects
				(font
					(size 1.27 1.27)
					(thickness 0.15)
				)
				(justify left bottom)
				(hide yes)
			)
		)
		(property "Description" "SMT test point"
			(at 255.27 231.14 0)
			(effects
				(font
					(size 1.27 1.27)
				)
				(hide yes)
			)
		)
		(property "MPN" ""
			(at 266.7 220.345 0)
			(effects
				(font
					(size 1.27 1.27)
					(thickness 0.15)
				)
				(justify left bottom)
				(hide yes)
			)
		)
		(property "Manufacturer" ""
			(at 261.62 220.345 0)
			(effects
				(font
					(size 1.27 1.27)
					(thickness 0.15)
				)
				(justify left bottom)
				(hide yes)
			)
		)
		(property "Author" "Antmicro"
			(at 264.16 220.345 0)
			(effects
				(font
					(size 1.27 1.27)
					(thickness 0.15)
				)
				(justify left bottom)
				(hide yes)
			)
		)
		(property "License" "Apache-2.0"
			(at 266.7 220.345 0)
			(effects
				(font
					(size 1.27 1.27)
					(thickness 0.15)
				)
				(justify left bottom)
				(hide yes)
			)
		)
		(pin "1"
		)
		(instances
			(project "gmsl-deserializer"
				(path ""
					(reference "TP18")
					(unit 1)
				)
			)
		)
	)
	(symbol
		(lib_id "antmicropower:GND")
		(at 102.87 250.19 0)
		(unit 1)
		(exclude_from_sim no)
		(in_bom yes)
		(on_board yes)
		(dnp no)
		(property "Reference" "#PWR034"
			(at 111.76 252.73 0)
			(effects
				(font
					(size 1.27 1.27)
					(thickness 0.15)
				)
				(justify left bottom)
				(hide yes)
			)
		)
		(property "Value" "GND"
			(at 102.87 254 0)
			(effects
				(font
					(size 1.27 1.27)
					(thickness 0.15)
				)
			)
		)
		(property "Footprint" ""
			(at 111.76 257.81 0)
			(effects
				(font
					(size 1.27 1.27)
					(thickness 0.15)
				)
				(justify left bottom)
				(hide yes)
			)
		)
		(property "Datasheet" ""
			(at 111.76 262.89 0)
			(effects
				(font
					(size 1.27 1.27)
					(thickness 0.15)
				)
				(justify left bottom)
				(hide yes)
			)
		)
		(property "Description" ""
			(at 102.87 250.19 0)
			(effects
				(font
					(size 1.27 1.27)
				)
				(hide yes)
			)
		)
		(property "Author" "Antmicro"
			(at 111.76 257.81 0)
			(effects
				(font
					(size 1.27 1.27)
					(thickness 0.15)
				)
				(justify left bottom)
				(hide yes)
			)
		)
		(property "License" "Apache-2.0"
			(at 111.76 260.35 0)
			(effects
				(font
					(size 1.27 1.27)
					(thickness 0.15)
				)
				(justify left bottom)
				(hide yes)
			)
		)
		(pin "1"
		)
		(instances
			(project "gmsl-deserializer"
				(path ""
					(reference "#PWR034")
					(unit 1)
				)
			)
		)
	)
	(symbol
		(lib_id "antmicroResistors0402:R_10k_0402")
		(at 309.88 229.87 90)
		(unit 1)
		(exclude_from_sim no)
		(in_bom no)
		(on_board yes)
		(dnp yes)
		(property "Reference" "R34"
			(at 311.785 226.0599 90)
			(effects
				(font
					(size 1.27 1.27)
					(thickness 0.15)
				)
				(justify right)
			)
		)
		(property "Value" "R_10k_0402"
			(at 322.58 209.55 0)
			(effects
				(font
					(size 1.27 1.27)
					(thickness 0.15)
				)
				(justify left bottom)
				(hide yes)
			)
		)
		(property "Footprint" "antmicro-footprints:R_0402_1005Metric"
			(at 325.12 209.55 0)
			(effects
				(font
					(size 1.27 1.27)
					(thickness 0.15)
				)
				(justify left bottom)
				(hide yes)
			)
		)
		(property "Datasheet" "https://www.bourns.com/docs/product-datasheets/cr.pdf"
			(at 327.66 209.55 0)
			(effects
				(font
					(size 1.27 1.27)
					(thickness 0.15)
				)
				(justify left bottom)
				(hide yes)
			)
		)
		(property "Description" "SMD Chip Resistor, 10 kohm, ± 1%, 62.5 mW, 0402 [1005 Metric], Thick Film, General Purpose"
			(at 309.88 229.87 0)
			(effects
				(font
					(size 1.27 1.27)
				)
				(hide yes)
			)
		)
		(property "MPN" "CR0402-FX-1002GLF"
			(at 330.2 209.55 0)
			(effects
				(font
					(size 1.27 1.27)
					(thickness 0.15)
				)
				(justify left bottom)
				(hide yes)
			)
		)
		(property "Manufacturer" "Bourns"
			(at 332.74 209.55 0)
			(effects
				(font
					(size 1.27 1.27)
					(thickness 0.15)
				)
				(justify left bottom)
				(hide yes)
			)
		)
		(property "License" "Apache-2.0"
			(at 335.28 209.55 0)
			(effects
				(font
					(size 1.27 1.27)
					(thickness 0.15)
				)
				(justify left bottom)
				(hide yes)
			)
		)
		(property "Author" "Antmicro"
			(at 337.82 209.55 0)
			(effects
				(font
					(size 1.27 1.27)
					(thickness 0.15)
				)
				(justify left bottom)
				(hide yes)
			)
		)
		(property "Val" "10k"
			(at 311.785 228.5999 90)
			(effects
				(font
					(size 1.27 1.27)
					(thickness 0.15)
				)
				(justify right)
			)
		)
		(property "Tolerance" "1%"
			(at 320.04 209.55 0)
			(effects
				(font
					(size 1.27 1.27)
				)
				(justify left bottom)
				(hide yes)
			)
		)
		(pin "1"
		)
		(pin "2"
		)
		(instances
			(project "gmsl-deserializer"
				(path ""
					(reference "R34")
					(unit 1)
				)
			)
		)
	)
	(symbol
		(lib_id "antmicropower:+1V8")
		(at 346.71 208.28 0)
		(unit 1)
		(exclude_from_sim no)
		(in_bom yes)
		(on_board yes)
		(dnp no)
		(property "Reference" "#PWR057"
			(at 361.95 210.82 0)
			(effects
				(font
					(size 1.27 1.27)
					(thickness 0.15)
				)
				(justify left bottom)
				(hide yes)
			)
		)
		(property "Value" "+1V8"
			(at 346.71 204.47 0)
			(effects
				(font
					(size 1.27 1.27)
					(thickness 0.15)
				)
			)
		)
		(property "Footprint" ""
			(at 361.95 215.9 0)
			(effects
				(font
					(size 1.27 1.27)
					(thickness 0.15)
				)
				(justify left bottom)
				(hide yes)
			)
		)
		(property "Datasheet" ""
			(at 361.95 218.44 0)
			(effects
				(font
					(size 1.27 1.27)
					(thickness 0.15)
				)
				(justify left bottom)
				(hide yes)
			)
		)
		(property "Description" ""
			(at 346.71 208.28 0)
			(effects
				(font
					(size 1.27 1.27)
				)
				(hide yes)
			)
		)
		(property "Author" "Antmicro"
			(at 361.95 215.9 0)
			(effects
				(font
					(size 1.27 1.27)
					(thickness 0.15)
				)
				(justify left bottom)
				(hide yes)
			)
		)
		(property "License" "Apache-2.0"
			(at 361.95 218.44 0)
			(effects
				(font
					(size 1.27 1.27)
					(thickness 0.15)
				)
				(justify left bottom)
				(hide yes)
			)
		)
		(pin "1"
		)
		(instances
			(project "gmsl-deserializer"
				(path ""
					(reference "#PWR057")
					(unit 1)
				)
			)
		)
	)
	(symbol
		(lib_id "antmicroLEDIndicationDiscrete:LED_G_0603_LTST-C190GKT")
		(at 388.62 142.24 270)
		(mirror x)
		(unit 1)
		(exclude_from_sim no)
		(in_bom yes)
		(on_board yes)
		(dnp no)
		(property "Reference" "D19"
			(at 392.43 138.43 90)
			(effects
				(font
					(size 1.27 1.27)
					(thickness 0.15)
				)
				(justify left)
			)
		)
		(property "Value" "LED_G_0603_LTST-C190GKT"
			(at 360.045 137.16 90)
			(effects
				(font
					(size 1.27 1.27)
					(thickness 0.15)
				)
				(justify left)
				(hide yes)
			)
		)
		(property "Footprint" "antmicro-footprints:LED_0603_1608Metric_G"
			(at 378.46 119.38 0)
			(effects
				(font
					(size 1.27 1.27)
					(thickness 0.15)
				)
				(justify left bottom)
				(hide yes)
			)
		)
		(property "Datasheet" "https://media.digikey.com/pdf/Data%20Sheets/Lite-On%20PDFs/LTST-C190GKT.pdf"
			(at 375.92 119.38 0)
			(effects
				(font
					(size 1.27 1.27)
					(thickness 0.15)
				)
				(justify left bottom)
				(hide yes)
			)
		)
		(property "Description" "LED, Green, SMD, 0603, 20 mA, 2.1 V, 569 nm"
			(at 388.62 142.24 0)
			(effects
				(font
					(size 1.27 1.27)
				)
				(hide yes)
			)
		)
		(property "MPN" "LTST-C190GKT"
			(at 392.43 139.7 90)
			(effects
				(font
					(size 1.27 1.27)
					(thickness 0.15)
				)
				(justify left bottom)
			)
		)
		(property "Manufacturer" "Lite-On"
			(at 370.84 119.38 0)
			(effects
				(font
					(size 1.27 1.27)
					(thickness 0.15)
				)
				(justify left bottom)
				(hide yes)
			)
		)
		(property "Author" "Antmicro"
			(at 368.3 119.38 0)
			(effects
				(font
					(size 1.27 1.27)
					(thickness 0.15)
				)
				(justify left bottom)
				(hide yes)
			)
		)
		(property "License" "Apache-2.0"
			(at 365.76 119.38 0)
			(effects
				(font
					(size 1.27 1.27)
					(thickness 0.15)
				)
				(justify left bottom)
				(hide yes)
			)
		)
		(property "VSD_class" "LED"
			(at 363.22 119.38 0)
			(effects
				(font
					(size 1.27 1.27)
				)
				(justify left bottom)
				(hide yes)
			)
		)
		(property "Color" "Green"
			(at 383.54 119.38 0)
			(effects
				(font
					(size 1.27 1.27)
				)
				(justify left bottom)
				(hide yes)
			)
		)
		(pin "1"
		)
		(pin "2"
		)
		(instances
			(project "gmsl-deserializer"
				(path ""
					(reference "D19")
					(unit 1)
				)
			)
		)
	)
	(symbol
		(lib_id "antmicropower:GND")
		(at 375.92 223.52 0)
		(unit 1)
		(exclude_from_sim no)
		(in_bom yes)
		(on_board yes)
		(dnp no)
		(property "Reference" "#PWR062"
			(at 384.81 226.06 0)
			(effects
				(font
					(size 1.27 1.27)
					(thickness 0.15)
				)
				(justify left bottom)
				(hide yes)
			)
		)
		(property "Value" "GND"
			(at 375.92 227.33 0)
			(effects
				(font
					(size 1.27 1.27)
					(thickness 0.15)
				)
			)
		)
		(property "Footprint" ""
			(at 384.81 231.14 0)
			(effects
				(font
					(size 1.27 1.27)
					(thickness 0.15)
				)
				(justify left bottom)
				(hide yes)
			)
		)
		(property "Datasheet" ""
			(at 384.81 236.22 0)
			(effects
				(font
					(size 1.27 1.27)
					(thickness 0.15)
				)
				(justify left bottom)
				(hide yes)
			)
		)
		(property "Description" ""
			(at 375.92 223.52 0)
			(effects
				(font
					(size 1.27 1.27)
				)
				(hide yes)
			)
		)
		(property "Author" "Antmicro"
			(at 384.81 231.14 0)
			(effects
				(font
					(size 1.27 1.27)
					(thickness 0.15)
				)
				(justify left bottom)
				(hide yes)
			)
		)
		(property "License" "Apache-2.0"
			(at 384.81 233.68 0)
			(effects
				(font
					(size 1.27 1.27)
					(thickness 0.15)
				)
				(justify left bottom)
				(hide yes)
			)
		)
		(pin "1"
		)
		(instances
			(project "gmsl-deserializer"
				(path ""
					(reference "#PWR062")
					(unit 1)
				)
			)
		)
	)
	(symbol
		(lib_id "antmicropower:+5V")
		(at 168.91 228.6 0)
		(unit 1)
		(exclude_from_sim no)
		(in_bom yes)
		(on_board yes)
		(dnp no)
		(property "Reference" "#PWR036"
			(at 184.15 231.14 0)
			(effects
				(font
					(size 1.27 1.27)
					(thickness 0.15)
				)
				(justify left bottom)
				(hide yes)
			)
		)
		(property "Value" "+5V"
			(at 168.91 224.79 0)
			(effects
				(font
					(size 1.27 1.27)
					(thickness 0.15)
				)
			)
		)
		(property "Footprint" ""
			(at 184.15 236.22 0)
			(effects
				(font
					(size 1.27 1.27)
					(thickness 0.15)
				)
				(justify left bottom)
				(hide yes)
			)
		)
		(property "Datasheet" ""
			(at 184.15 238.76 0)
			(effects
				(font
					(size 1.27 1.27)
					(thickness 0.15)
				)
				(justify left bottom)
				(hide yes)
			)
		)
		(property "Description" ""
			(at 168.91 228.6 0)
			(effects
				(font
					(size 1.27 1.27)
				)
				(hide yes)
			)
		)
		(property "Author" "Antmicro"
			(at 184.15 236.22 0)
			(effects
				(font
					(size 1.27 1.27)
					(thickness 0.15)
				)
				(justify left bottom)
				(hide yes)
			)
		)
		(property "License" "Apache-2.0"
			(at 184.15 238.76 0)
			(effects
				(font
					(size 1.27 1.27)
					(thickness 0.15)
				)
				(justify left bottom)
				(hide yes)
			)
		)
		(pin "1"
		)
		(instances
			(project "gmsl-deserializer"
				(path ""
					(reference "#PWR036")
					(unit 1)
				)
			)
		)
	)
	(symbol
		(lib_id "antmicroTestPoints:TP_0.75mm_SMD")
		(at 110.49 223.52 90)
		(unit 1)
		(exclude_from_sim no)
		(in_bom yes)
		(on_board yes)
		(dnp no)
		(property "Reference" "TP20"
			(at 109.22 218.44 90)
			(effects
				(font
					(size 1.27 1.27)
					(thickness 0.15)
				)
				(justify right)
			)
		)
		(property "Value" "TP_0.75mm_SMD"
			(at 114.3 212.725 0)
			(effects
				(font
					(size 1.27 1.27)
					(thickness 0.15)
				)
				(justify left bottom)
				(hide yes)
			)
		)
		(property "Footprint" "antmicro-footprints:TP_SMD_0.75mm"
			(at 116.84 212.725 0)
			(effects
				(font
					(size 1.27 1.27)
					(thickness 0.15)
				)
				(justify left bottom)
				(hide yes)
			)
		)
		(property "Datasheet" ""
			(at 123.19 205.74 0)
			(effects
				(font
					(size 1.27 1.27)
					(thickness 0.15)
				)
				(justify left bottom)
				(hide yes)
			)
		)
		(property "Description" "SMT test point"
			(at 110.49 223.52 0)
			(effects
				(font
					(size 1.27 1.27)
				)
				(hide yes)
			)
		)
		(property "MPN" ""
			(at 121.92 212.725 0)
			(effects
				(font
					(size 1.27 1.27)
					(thickness 0.15)
				)
				(justify left bottom)
				(hide yes)
			)
		)
		(property "Manufacturer" ""
			(at 116.84 212.725 0)
			(effects
				(font
					(size 1.27 1.27)
					(thickness 0.15)
				)
				(justify left bottom)
				(hide yes)
			)
		)
		(property "Author" "Antmicro"
			(at 119.38 212.725 0)
			(effects
				(font
					(size 1.27 1.27)
					(thickness 0.15)
				)
				(justify left bottom)
				(hide yes)
			)
		)
		(property "License" "Apache-2.0"
			(at 121.92 212.725 0)
			(effects
				(font
					(size 1.27 1.27)
					(thickness 0.15)
				)
				(justify left bottom)
				(hide yes)
			)
		)
		(pin "1"
		)
		(instances
			(project "gmsl-deserializer"
				(path ""
					(reference "TP20")
					(unit 1)
				)
			)
		)
	)
	(symbol
		(lib_id "antmicroResistors0402:R_5k1_0402")
		(at 121.92 97.79 0)
		(unit 1)
		(exclude_from_sim no)
		(in_bom yes)
		(on_board yes)
		(dnp no)
		(fields_autoplaced yes)
		(property "Reference" "R25"
			(at 124.46 92.075 0)
			(effects
				(font
					(size 1.27 1.27)
					(thickness 0.15)
				)
			)
		)
		(property "Value" "R_5k1_0402"
			(at 142.24 110.49 0)
			(effects
				(font
					(size 1.27 1.27)
					(thickness 0.15)
				)
				(justify left bottom)
				(hide yes)
			)
		)
		(property "Footprint" "antmicro-footprints:R_0402_1005Metric"
			(at 142.24 113.03 0)
			(effects
				(font
					(size 1.27 1.27)
					(thickness 0.15)
				)
				(justify left bottom)
				(hide yes)
			)
		)
		(property "Datasheet" "https://www.bourns.com/docs/product-datasheets/cr.pdf"
			(at 142.24 115.57 0)
			(effects
				(font
					(size 1.27 1.27)
					(thickness 0.15)
				)
				(justify left bottom)
				(hide yes)
			)
		)
		(property "Description" "SMD Chip Resistor, 5.1 kohm, ± 1%, 63 mW, 0402 [1005 Metric], Thick Film, General Purpose"
			(at 121.92 97.79 0)
			(effects
				(font
					(size 1.27 1.27)
				)
				(hide yes)
			)
		)
		(property "MPN" "CR0402-FX-5101GLF"
			(at 142.24 118.11 0)
			(effects
				(font
					(size 1.27 1.27)
					(thickness 0.15)
				)
				(justify left bottom)
				(hide yes)
			)
		)
		(property "Manufacturer" "Bourns"
			(at 142.24 120.65 0)
			(effects
				(font
					(size 1.27 1.27)
					(thickness 0.15)
				)
				(justify left bottom)
				(hide yes)
			)
		)
		(property "License" "Apache-2.0"
			(at 142.24 123.19 0)
			(effects
				(font
					(size 1.27 1.27)
					(thickness 0.15)
				)
				(justify left bottom)
				(hide yes)
			)
		)
		(property "Author" "Antmicro"
			(at 142.24 125.73 0)
			(effects
				(font
					(size 1.27 1.27)
					(thickness 0.15)
				)
				(justify left bottom)
				(hide yes)
			)
		)
		(property "Val" "5k1"
			(at 124.46 94.615 0)
			(effects
				(font
					(size 1.27 1.27)
					(thickness 0.15)
				)
			)
		)
		(property "Tolerance" "1%"
			(at 142.24 107.95 0)
			(effects
				(font
					(size 1.27 1.27)
				)
				(justify left bottom)
				(hide yes)
			)
		)
		(pin "1"
		)
		(pin "2"
		)
		(instances
			(project "gmsl-deserializer"
				(path ""
					(reference "R25")
					(unit 1)
				)
			)
		)
	)
	(symbol
		(lib_id "antmicroResistors0603:R_0R_22.4A_0603")
		(at 353.06 132.08 0)
		(unit 1)
		(exclude_from_sim no)
		(in_bom yes)
		(on_board yes)
		(dnp no)
		(property "Reference" "R41"
			(at 355.6 127 0)
			(effects
				(font
					(size 1.27 1.27)
					(thickness 0.15)
				)
			)
		)
		(property "Value" "R_0R_22.4A_0603"
			(at 355.6 126.365 0)
			(effects
				(font
					(size 1.27 1.27)
					(thickness 0.15)
				)
				(hide yes)
			)
		)
		(property "Footprint" "antmicro-footprints:R_0603_1608Metric"
			(at 368.3 142.24 0)
			(effects
				(font
					(size 1.27 1.27)
					(thickness 0.15)
				)
				(justify left bottom)
				(hide yes)
			)
		)
		(property "Datasheet" "https://fscdn.rohm.com/en/products/databook/datasheet/passive/resistor/chip_resistor/pmr-jpw-e.pdf"
			(at 368.3 144.78 0)
			(effects
				(font
					(size 1.27 1.27)
					(thickness 0.15)
				)
				(justify left bottom)
				(hide yes)
			)
		)
		(property "Description" "SMD Chip Resistor"
			(at 353.06 132.08 0)
			(effects
				(font
					(size 1.27 1.27)
				)
				(hide yes)
			)
		)
		(property "MPN" "PMR03EZPJ000"
			(at 368.3 147.32 0)
			(effects
				(font
					(size 1.27 1.27)
					(thickness 0.15)
				)
				(justify left bottom)
				(hide yes)
			)
		)
		(property "Manufacturer" "ROHM Semiconductor"
			(at 368.3 149.86 0)
			(effects
				(font
					(size 1.27 1.27)
					(thickness 0.15)
				)
				(justify left bottom)
				(hide yes)
			)
		)
		(property "Val" "0R"
			(at 355.6 129.54 0)
			(effects
				(font
					(size 1.27 1.27)
					(thickness 0.15)
				)
			)
		)
		(property "Max. Curr." "22.4A"
			(at 355.6 134.62 0)
			(effects
				(font
					(size 1.27 1.27)
					(thickness 0.15)
				)
			)
		)
		(property "Author" "Antmicro"
			(at 368.3 154.94 0)
			(effects
				(font
					(size 1.27 1.27)
					(thickness 0.15)
				)
				(justify left bottom)
				(hide yes)
			)
		)
		(property "License" "Apache-2.0"
			(at 368.3 157.48 0)
			(effects
				(font
					(size 1.27 1.27)
					(thickness 0.15)
				)
				(justify left bottom)
				(hide yes)
			)
		)
		(property "Tolerance" "template_tolerance"
			(at 373.38 142.24 0)
			(effects
				(font
					(size 1.27 1.27)
				)
				(justify left bottom)
				(hide yes)
			)
		)
		(pin "1"
		)
		(pin "2"
		)
		(instances
			(project "gmsl-deserializer"
				(path ""
					(reference "R41")
					(unit 1)
				)
			)
		)
	)
	(symbol
		(lib_id "antmicropower:GND")
		(at 327.66 73.66 0)
		(unit 1)
		(exclude_from_sim no)
		(in_bom yes)
		(on_board yes)
		(dnp no)
		(property "Reference" "#PWR052"
			(at 336.55 76.2 0)
			(effects
				(font
					(size 1.27 1.27)
					(thickness 0.15)
				)
				(justify left bottom)
				(hide yes)
			)
		)
		(property "Value" "GND"
			(at 327.66 77.47 0)
			(effects
				(font
					(size 1.27 1.27)
					(thickness 0.15)
				)
			)
		)
		(property "Footprint" ""
			(at 336.55 81.28 0)
			(effects
				(font
					(size 1.27 1.27)
					(thickness 0.15)
				)
				(justify left bottom)
				(hide yes)
			)
		)
		(property "Datasheet" ""
			(at 336.55 86.36 0)
			(effects
				(font
					(size 1.27 1.27)
					(thickness 0.15)
				)
				(justify left bottom)
				(hide yes)
			)
		)
		(property "Description" ""
			(at 327.66 73.66 0)
			(effects
				(font
					(size 1.27 1.27)
				)
				(hide yes)
			)
		)
		(property "Author" "Antmicro"
			(at 336.55 81.28 0)
			(effects
				(font
					(size 1.27 1.27)
					(thickness 0.15)
				)
				(justify left bottom)
				(hide yes)
			)
		)
		(property "License" "Apache-2.0"
			(at 336.55 83.82 0)
			(effects
				(font
					(size 1.27 1.27)
					(thickness 0.15)
				)
				(justify left bottom)
				(hide yes)
			)
		)
		(pin "1"
		)
		(instances
			(project "gmsl-deserializer"
				(path ""
					(reference "#PWR052")
					(unit 1)
				)
			)
		)
	)
	(symbol
		(lib_id "antmicroResistors0402:R_1M_0402")
		(at 102.87 248.92 90)
		(unit 1)
		(exclude_from_sim no)
		(in_bom yes)
		(on_board yes)
		(dnp no)
		(fields_autoplaced yes)
		(property "Reference" "R23"
			(at 105.41 245.1099 90)
			(effects
				(font
					(size 1.27 1.27)
					(thickness 0.15)
				)
				(justify right)
			)
		)
		(property "Value" "R_1M_0402"
			(at 115.57 228.6 0)
			(effects
				(font
					(size 1.27 1.27)
					(thickness 0.15)
				)
				(justify left bottom)
				(hide yes)
			)
		)
		(property "Footprint" "antmicro-footprints:R_0402_1005Metric"
			(at 118.11 228.6 0)
			(effects
				(font
					(size 1.27 1.27)
					(thickness 0.15)
				)
				(justify left bottom)
				(hide yes)
			)
		)
		(property "Datasheet" "https://www.bourns.com/docs/product-datasheets/cr.pdf"
			(at 120.65 228.6 0)
			(effects
				(font
					(size 1.27 1.27)
					(thickness 0.15)
				)
				(justify left bottom)
				(hide yes)
			)
		)
		(property "Description" "SMD Chip Resistor, 1 Mohm, ± 1%, 62.5 mW, 0402 [1005 Metric], Thick Film, General Purpose"
			(at 102.87 248.92 0)
			(effects
				(font
					(size 1.27 1.27)
				)
				(hide yes)
			)
		)
		(property "MPN" "CR0402-FX-1004GLF"
			(at 123.19 228.6 0)
			(effects
				(font
					(size 1.27 1.27)
					(thickness 0.15)
				)
				(justify left bottom)
				(hide yes)
			)
		)
		(property "Manufacturer" "Bourns"
			(at 125.73 228.6 0)
			(effects
				(font
					(size 1.27 1.27)
					(thickness 0.15)
				)
				(justify left bottom)
				(hide yes)
			)
		)
		(property "License" "Apache-2.0"
			(at 128.27 228.6 0)
			(effects
				(font
					(size 1.27 1.27)
					(thickness 0.15)
				)
				(justify left bottom)
				(hide yes)
			)
		)
		(property "Author" "Antmicro"
			(at 130.81 228.6 0)
			(effects
				(font
					(size 1.27 1.27)
					(thickness 0.15)
				)
				(justify left bottom)
				(hide yes)
			)
		)
		(property "Val" "1M"
			(at 105.41 247.6499 90)
			(effects
				(font
					(size 1.27 1.27)
					(thickness 0.15)
				)
				(justify right)
			)
		)
		(property "Tolerance" "1%"
			(at 113.03 228.6 0)
			(effects
				(font
					(size 1.27 1.27)
				)
				(justify left bottom)
				(hide yes)
			)
		)
		(pin "1"
		)
		(pin "2"
		)
		(instances
			(project "gmsl-deserializer"
				(path ""
					(reference "R23")
					(unit 1)
				)
			)
		)
	)
	(symbol
		(lib_id "antmicropower:GND")
		(at 334.01 224.79 0)
		(unit 1)
		(exclude_from_sim no)
		(in_bom yes)
		(on_board yes)
		(dnp no)
		(property "Reference" "#PWR0111"
			(at 342.9 227.33 0)
			(effects
				(font
					(size 1.27 1.27)
					(thickness 0.15)
				)
				(justify left bottom)
				(hide yes)
			)
		)
		(property "Value" "GND"
			(at 334.01 228.6 0)
			(effects
				(font
					(size 1.27 1.27)
					(thickness 0.15)
				)
			)
		)
		(property "Footprint" ""
			(at 342.9 232.41 0)
			(effects
				(font
					(size 1.27 1.27)
					(thickness 0.15)
				)
				(justify left bottom)
				(hide yes)
			)
		)
		(property "Datasheet" ""
			(at 342.9 237.49 0)
			(effects
				(font
					(size 1.27 1.27)
					(thickness 0.15)
				)
				(justify left bottom)
				(hide yes)
			)
		)
		(property "Description" ""
			(at 334.01 224.79 0)
			(effects
				(font
					(size 1.27 1.27)
				)
				(hide yes)
			)
		)
		(property "Author" "Antmicro"
			(at 342.9 232.41 0)
			(effects
				(font
					(size 1.27 1.27)
					(thickness 0.15)
				)
				(justify left bottom)
				(hide yes)
			)
		)
		(property "License" "Apache-2.0"
			(at 342.9 234.95 0)
			(effects
				(font
					(size 1.27 1.27)
					(thickness 0.15)
				)
				(justify left bottom)
				(hide yes)
			)
		)
		(pin "1"
		)
		(instances
			(project "gmsl-deserializer"
				(path ""
					(reference "#PWR0111")
					(unit 1)
				)
			)
		)
	)
	(symbol
		(lib_id "antmicroTestPoints:TP_0.75mm_SMD")
		(at 331.47 55.88 90)
		(unit 1)
		(exclude_from_sim no)
		(in_bom yes)
		(on_board yes)
		(dnp no)
		(property "Reference" "TP13"
			(at 330.2 50.8 90)
			(effects
				(font
					(size 1.27 1.27)
					(thickness 0.15)
				)
				(justify right)
			)
		)
		(property "Value" "TP_0.75mm_SMD"
			(at 335.28 45.085 0)
			(effects
				(font
					(size 1.27 1.27)
					(thickness 0.15)
				)
				(justify left bottom)
				(hide yes)
			)
		)
		(property "Footprint" "antmicro-footprints:TP_SMD_0.75mm"
			(at 337.82 45.085 0)
			(effects
				(font
					(size 1.27 1.27)
					(thickness 0.15)
				)
				(justify left bottom)
				(hide yes)
			)
		)
		(property "Datasheet" ""
			(at 344.17 38.1 0)
			(effects
				(font
					(size 1.27 1.27)
					(thickness 0.15)
				)
				(justify left bottom)
				(hide yes)
			)
		)
		(property "Description" "SMT test point"
			(at 331.47 55.88 0)
			(effects
				(font
					(size 1.27 1.27)
				)
				(hide yes)
			)
		)
		(property "MPN" ""
			(at 342.9 45.085 0)
			(effects
				(font
					(size 1.27 1.27)
					(thickness 0.15)
				)
				(justify left bottom)
				(hide yes)
			)
		)
		(property "Manufacturer" ""
			(at 337.82 45.085 0)
			(effects
				(font
					(size 1.27 1.27)
					(thickness 0.15)
				)
				(justify left bottom)
				(hide yes)
			)
		)
		(property "Author" "Antmicro"
			(at 340.36 45.085 0)
			(effects
				(font
					(size 1.27 1.27)
					(thickness 0.15)
				)
				(justify left bottom)
				(hide yes)
			)
		)
		(property "License" "Apache-2.0"
			(at 342.9 45.085 0)
			(effects
				(font
					(size 1.27 1.27)
					(thickness 0.15)
				)
				(justify left bottom)
				(hide yes)
			)
		)
		(pin "1"
		)
		(instances
			(project "gmsl-deserializer"
				(path ""
					(reference "TP13")
					(unit 1)
				)
			)
		)
	)
	(symbol
		(lib_id "antmicropower:GND")
		(at 245.11 240.03 0)
		(unit 1)
		(exclude_from_sim no)
		(in_bom yes)
		(on_board yes)
		(dnp no)
		(property "Reference" "#PWR040"
			(at 254 242.57 0)
			(effects
				(font
					(size 1.27 1.27)
					(thickness 0.15)
				)
				(justify left bottom)
				(hide yes)
			)
		)
		(property "Value" "GND"
			(at 245.11 243.84 0)
			(effects
				(font
					(size 1.27 1.27)
					(thickness 0.15)
				)
			)
		)
		(property "Footprint" ""
			(at 254 247.65 0)
			(effects
				(font
					(size 1.27 1.27)
					(thickness 0.15)
				)
				(justify left bottom)
				(hide yes)
			)
		)
		(property "Datasheet" ""
			(at 254 252.73 0)
			(effects
				(font
					(size 1.27 1.27)
					(thickness 0.15)
				)
				(justify left bottom)
				(hide yes)
			)
		)
		(property "Description" ""
			(at 245.11 240.03 0)
			(effects
				(font
					(size 1.27 1.27)
				)
				(hide yes)
			)
		)
		(property "Author" "Antmicro"
			(at 254 247.65 0)
			(effects
				(font
					(size 1.27 1.27)
					(thickness 0.15)
				)
				(justify left bottom)
				(hide yes)
			)
		)
		(property "License" "Apache-2.0"
			(at 254 250.19 0)
			(effects
				(font
					(size 1.27 1.27)
					(thickness 0.15)
				)
				(justify left bottom)
				(hide yes)
			)
		)
		(pin "1"
		)
		(instances
			(project "gmsl-deserializer"
				(path ""
					(reference "#PWR040")
					(unit 1)
				)
			)
		)
	)
	(symbol
		(lib_id "antmicropower:GND")
		(at 198.12 238.76 0)
		(unit 1)
		(exclude_from_sim no)
		(in_bom yes)
		(on_board yes)
		(dnp no)
		(property "Reference" "#PWR038"
			(at 207.01 241.3 0)
			(effects
				(font
					(size 1.27 1.27)
					(thickness 0.15)
				)
				(justify left bottom)
				(hide yes)
			)
		)
		(property "Value" "GND"
			(at 198.12 242.57 0)
			(effects
				(font
					(size 1.27 1.27)
					(thickness 0.15)
				)
			)
		)
		(property "Footprint" ""
			(at 207.01 246.38 0)
			(effects
				(font
					(size 1.27 1.27)
					(thickness 0.15)
				)
				(justify left bottom)
				(hide yes)
			)
		)
		(property "Datasheet" ""
			(at 207.01 251.46 0)
			(effects
				(font
					(size 1.27 1.27)
					(thickness 0.15)
				)
				(justify left bottom)
				(hide yes)
			)
		)
		(property "Description" ""
			(at 198.12 238.76 0)
			(effects
				(font
					(size 1.27 1.27)
				)
				(hide yes)
			)
		)
		(property "Author" "Antmicro"
			(at 207.01 246.38 0)
			(effects
				(font
					(size 1.27 1.27)
					(thickness 0.15)
				)
				(justify left bottom)
				(hide yes)
			)
		)
		(property "License" "Apache-2.0"
			(at 207.01 248.92 0)
			(effects
				(font
					(size 1.27 1.27)
					(thickness 0.15)
				)
				(justify left bottom)
				(hide yes)
			)
		)
		(pin "1"
		)
		(instances
			(project "gmsl-deserializer"
				(path ""
					(reference "#PWR038")
					(unit 1)
				)
			)
		)
	)
	(symbol
		(lib_id "antmicropower:+12V")
		(at 129.54 223.52 0)
		(unit 1)
		(exclude_from_sim no)
		(in_bom yes)
		(on_board yes)
		(dnp no)
		(fields_autoplaced yes)
		(property "Reference" "#PWR035"
			(at 129.54 227.33 0)
			(effects
				(font
					(size 1.27 1.27)
				)
				(hide yes)
			)
		)
		(property "Value" "+12V"
			(at 129.54 218.44 0)
			(effects
				(font
					(size 1.27 1.27)
				)
			)
		)
		(property "Footprint" ""
			(at 129.54 223.52 0)
			(effects
				(font
					(size 1.27 1.27)
				)
				(hide yes)
			)
		)
		(property "Datasheet" ""
			(at 129.54 223.52 0)
			(effects
				(font
					(size 1.27 1.27)
				)
				(hide yes)
			)
		)
		(property "Description" ""
			(at 129.54 223.52 0)
			(effects
				(font
					(size 1.27 1.27)
				)
				(hide yes)
			)
		)
		(pin "1"
		)
		(instances
			(project "gmsl-deserializer"
				(path ""
					(reference "#PWR035")
					(unit 1)
				)
			)
		)
	)
	(symbol
		(lib_id "antmicropower:+12V")
		(at 270.51 229.87 0)
		(unit 1)
		(exclude_from_sim no)
		(in_bom yes)
		(on_board yes)
		(dnp no)
		(fields_autoplaced yes)
		(property "Reference" "#PWR041"
			(at 270.51 233.68 0)
			(effects
				(font
					(size 1.27 1.27)
				)
				(hide yes)
			)
		)
		(property "Value" "+12V"
			(at 270.51 224.79 0)
			(effects
				(font
					(size 1.27 1.27)
				)
			)
		)
		(property "Footprint" ""
			(at 270.51 229.87 0)
			(effects
				(font
					(size 1.27 1.27)
				)
				(hide yes)
			)
		)
		(property "Datasheet" ""
			(at 270.51 229.87 0)
			(effects
				(font
					(size 1.27 1.27)
				)
				(hide yes)
			)
		)
		(property "Description" ""
			(at 270.51 229.87 0)
			(effects
				(font
					(size 1.27 1.27)
				)
				(hide yes)
			)
		)
		(pin "1"
		)
		(instances
			(project "gmsl-deserializer"
				(path ""
					(reference "#PWR041")
					(unit 1)
				)
			)
		)
	)
	(symbol
		(lib_id "antmicroTestPoints:TP_0.75mm_SMD")
		(at 332.74 130.81 90)
		(unit 1)
		(exclude_from_sim no)
		(in_bom yes)
		(on_board yes)
		(dnp no)
		(property "Reference" "TP14"
			(at 331.47 125.73 90)
			(effects
				(font
					(size 1.27 1.27)
					(thickness 0.15)
				)
				(justify right)
			)
		)
		(property "Value" "TP_0.75mm_SMD"
			(at 336.55 120.015 0)
			(effects
				(font
					(size 1.27 1.27)
					(thickness 0.15)
				)
				(justify left bottom)
				(hide yes)
			)
		)
		(property "Footprint" "antmicro-footprints:TP_SMD_0.75mm"
			(at 339.09 120.015 0)
			(effects
				(font
					(size 1.27 1.27)
					(thickness 0.15)
				)
				(justify left bottom)
				(hide yes)
			)
		)
		(property "Datasheet" ""
			(at 345.44 113.03 0)
			(effects
				(font
					(size 1.27 1.27)
					(thickness 0.15)
				)
				(justify left bottom)
				(hide yes)
			)
		)
		(property "Description" "SMT test point"
			(at 332.74 130.81 0)
			(effects
				(font
					(size 1.27 1.27)
				)
				(hide yes)
			)
		)
		(property "MPN" ""
			(at 344.17 120.015 0)
			(effects
				(font
					(size 1.27 1.27)
					(thickness 0.15)
				)
				(justify left bottom)
				(hide yes)
			)
		)
		(property "Manufacturer" ""
			(at 339.09 120.015 0)
			(effects
				(font
					(size 1.27 1.27)
					(thickness 0.15)
				)
				(justify left bottom)
				(hide yes)
			)
		)
		(property "Author" "Antmicro"
			(at 341.63 120.015 0)
			(effects
				(font
					(size 1.27 1.27)
					(thickness 0.15)
				)
				(justify left bottom)
				(hide yes)
			)
		)
		(property "License" "Apache-2.0"
			(at 344.17 120.015 0)
			(effects
				(font
					(size 1.27 1.27)
					(thickness 0.15)
				)
				(justify left bottom)
				(hide yes)
			)
		)
		(pin "1"
		)
		(instances
			(project "gmsl-deserializer"
				(path ""
					(reference "TP14")
					(unit 1)
				)
			)
		)
	)
	(symbol
		(lib_id "antmicroResistors0402:R_1k65_0402")
		(at 31.75 243.84 90)
		(unit 1)
		(exclude_from_sim no)
		(in_bom yes)
		(on_board yes)
		(dnp no)
		(fields_autoplaced yes)
		(property "Reference" "R76"
			(at 34.29 240.03 90)
			(effects
				(font
					(size 1.27 1.27)
					(thickness 0.15)
				)
				(justify right)
			)
		)
		(property "Value" "R_1k65_0402"
			(at 44.45 223.52 0)
			(effects
				(font
					(size 1.27 1.27)
					(thickness 0.15)
				)
				(justify left bottom)
				(hide yes)
			)
		)
		(property "Footprint" "antmicro-footprints:R_0402_1005Metric"
			(at 46.99 223.52 0)
			(effects
				(font
					(size 1.27 1.27)
					(thickness 0.15)
				)
				(justify left bottom)
				(hide yes)
			)
		)
		(property "Datasheet" "https://www.farnell.com/datasheets/3795017.pdf"
			(at 49.53 223.52 0)
			(effects
				(font
					(size 1.27 1.27)
					(thickness 0.15)
				)
				(justify left bottom)
				(hide yes)
			)
		)
		(property "Description" "SMD Chip Resistor, 1.65 kohm, ± 1%, 63 mW, 0402 [1005 Metric], Thick Film, General Purpose"
			(at 31.75 243.84 0)
			(effects
				(font
					(size 1.27 1.27)
				)
				(hide yes)
			)
		)
		(property "MPN" "RC0402FR-071K65L"
			(at 52.07 223.52 0)
			(effects
				(font
					(size 1.27 1.27)
					(thickness 0.15)
				)
				(justify left bottom)
				(hide yes)
			)
		)
		(property "Manufacturer" "YAGEO"
			(at 54.61 223.52 0)
			(effects
				(font
					(size 1.27 1.27)
					(thickness 0.15)
				)
				(justify left bottom)
				(hide yes)
			)
		)
		(property "License" "Apache-2.0"
			(at 57.15 223.52 0)
			(effects
				(font
					(size 1.27 1.27)
					(thickness 0.15)
				)
				(justify left bottom)
				(hide yes)
			)
		)
		(property "Author" "Antmicro"
			(at 59.69 223.52 0)
			(effects
				(font
					(size 1.27 1.27)
					(thickness 0.15)
				)
				(justify left bottom)
				(hide yes)
			)
		)
		(property "Val" "1k65"
			(at 34.29 242.57 90)
			(effects
				(font
					(size 1.27 1.27)
					(thickness 0.15)
				)
				(justify right)
			)
		)
		(property "Tolerance" "1%"
			(at 41.91 223.52 0)
			(effects
				(font
					(size 1.27 1.27)
				)
				(justify left bottom)
				(hide yes)
			)
		)
		(property "Public" ""
			(at 62.23 223.52 0)
			(effects
				(font
					(size 1.27 1.27)
				)
				(justify left bottom)
				(hide yes)
			)
		)
		(pin "1"
		)
		(pin "2"
		)
		(instances
			(project "gmsl-deserializer"
				(path ""
					(reference "R76")
					(unit 1)
				)
			)
		)
	)
	(symbol
		(lib_id "antmicropower:PWR_FLAG")
		(at 76.2 223.52 0)
		(unit 1)
		(exclude_from_sim no)
		(in_bom yes)
		(on_board yes)
		(dnp no)
		(property "Reference" "#FLG01"
			(at 76.2 221.615 0)
			(effects
				(font
					(size 1.27 1.27)
				)
				(hide yes)
			)
		)
		(property "Value" "PWR_FLAG"
			(at 76.2 219.71 0)
			(effects
				(font
					(size 1.27 1.27)
				)
			)
		)
		(property "Footprint" ""
			(at 76.2 223.52 0)
			(effects
				(font
					(size 1.27 1.27)
				)
				(hide yes)
			)
		)
		(property "Datasheet" ""
			(at 76.2 223.52 0)
			(effects
				(font
					(size 1.27 1.27)
				)
				(hide yes)
			)
		)
		(property "Description" ""
			(at 76.2 223.52 0)
			(effects
				(font
					(size 1.27 1.27)
				)
				(hide yes)
			)
		)
		(pin "1"
		)
		(instances
			(project "gmsl-deserializer"
				(path ""
					(reference "#FLG01")
					(unit 1)
				)
			)
		)
	)
	(symbol
		(lib_id "antmicropower:GND")
		(at 309.88 229.87 0)
		(unit 1)
		(exclude_from_sim no)
		(in_bom yes)
		(on_board yes)
		(dnp no)
		(property "Reference" "#PWR051"
			(at 318.77 232.41 0)
			(effects
				(font
					(size 1.27 1.27)
					(thickness 0.15)
				)
				(justify left bottom)
				(hide yes)
			)
		)
		(property "Value" "GND"
			(at 309.88 233.68 0)
			(effects
				(font
					(size 1.27 1.27)
					(thickness 0.15)
				)
			)
		)
		(property "Footprint" ""
			(at 318.77 237.49 0)
			(effects
				(font
					(size 1.27 1.27)
					(thickness 0.15)
				)
				(justify left bottom)
				(hide yes)
			)
		)
		(property "Datasheet" ""
			(at 318.77 242.57 0)
			(effects
				(font
					(size 1.27 1.27)
					(thickness 0.15)
				)
				(justify left bottom)
				(hide yes)
			)
		)
		(property "Description" ""
			(at 309.88 229.87 0)
			(effects
				(font
					(size 1.27 1.27)
				)
				(hide yes)
			)
		)
		(property "Author" "Antmicro"
			(at 318.77 237.49 0)
			(effects
				(font
					(size 1.27 1.27)
					(thickness 0.15)
				)
				(justify left bottom)
				(hide yes)
			)
		)
		(property "License" "Apache-2.0"
			(at 318.77 240.03 0)
			(effects
				(font
					(size 1.27 1.27)
					(thickness 0.15)
				)
				(justify left bottom)
				(hide yes)
			)
		)
		(pin "1"
		)
		(instances
			(project "gmsl-deserializer"
				(path ""
					(reference "#PWR051")
					(unit 1)
				)
			)
		)
	)
	(symbol
		(lib_id "antmicroTestPoints:TP_0.75mm_SMD")
		(at 369.57 54.61 90)
		(unit 1)
		(exclude_from_sim no)
		(in_bom yes)
		(on_board yes)
		(dnp no)
		(property "Reference" "TP28"
			(at 368.3 49.53 90)
			(effects
				(font
					(size 1.27 1.27)
					(thickness 0.15)
				)
				(justify right)
			)
		)
		(property "Value" "TP_0.75mm_SMD"
			(at 373.38 43.815 0)
			(effects
				(font
					(size 1.27 1.27)
					(thickness 0.15)
				)
				(justify left bottom)
				(hide yes)
			)
		)
		(property "Footprint" "antmicro-footprints:TP_SMD_0.75mm"
			(at 375.92 43.815 0)
			(effects
				(font
					(size 1.27 1.27)
					(thickness 0.15)
				)
				(justify left bottom)
				(hide yes)
			)
		)
		(property "Datasheet" ""
			(at 382.27 36.83 0)
			(effects
				(font
					(size 1.27 1.27)
					(thickness 0.15)
				)
				(justify left bottom)
				(hide yes)
			)
		)
		(property "Description" "SMT test point"
			(at 369.57 54.61 0)
			(effects
				(font
					(size 1.27 1.27)
				)
				(hide yes)
			)
		)
		(property "MPN" ""
			(at 381 43.815 0)
			(effects
				(font
					(size 1.27 1.27)
					(thickness 0.15)
				)
				(justify left bottom)
				(hide yes)
			)
		)
		(property "Manufacturer" ""
			(at 375.92 43.815 0)
			(effects
				(font
					(size 1.27 1.27)
					(thickness 0.15)
				)
				(justify left bottom)
				(hide yes)
			)
		)
		(property "Author" "Antmicro"
			(at 378.46 43.815 0)
			(effects
				(font
					(size 1.27 1.27)
					(thickness 0.15)
				)
				(justify left bottom)
				(hide yes)
			)
		)
		(property "License" "Apache-2.0"
			(at 381 43.815 0)
			(effects
				(font
					(size 1.27 1.27)
					(thickness 0.15)
				)
				(justify left bottom)
				(hide yes)
			)
		)
		(pin "1"
		)
		(instances
			(project "gmsl-deserializer"
				(path ""
					(reference "TP28")
					(unit 1)
				)
			)
		)
	)
	(symbol
		(lib_id "antmicroCapacitors0402:C_10n_0402")
		(at 88.9 148.59 90)
		(unit 1)
		(exclude_from_sim no)
		(in_bom yes)
		(on_board yes)
		(dnp no)
		(property "Reference" "C13"
			(at 89.535 144.145 90)
			(effects
				(font
					(size 1.27 1.27)
					(thickness 0.15)
				)
				(justify right)
			)
		)
		(property "Value" "C_10n_0402"
			(at 99.06 128.27 0)
			(effects
				(font
					(size 1.27 1.27)
					(thickness 0.15)
				)
				(justify left bottom)
				(hide yes)
			)
		)
		(property "Footprint" "antmicro-footprints:C_0402_1005Metric"
			(at 101.6 128.27 0)
			(effects
				(font
					(size 1.27 1.27)
					(thickness 0.15)
				)
				(justify left bottom)
				(hide yes)
			)
		)
		(property "Datasheet" "https://www.murata.com/products/productdetail?partno=GRM155R71H103KA88%23"
			(at 104.14 128.27 0)
			(effects
				(font
					(size 1.27 1.27)
					(thickness 0.15)
				)
				(justify left bottom)
				(hide yes)
			)
		)
		(property "Description" "SMD Multilayer Ceramic Capacitor, 10000 pF, 50 V, 0402 [1005 Metric], ± 10%, X7R, GRM Series"
			(at 88.9 148.59 0)
			(effects
				(font
					(size 1.27 1.27)
				)
				(hide yes)
			)
		)
		(property "MPN" "GRM155R71H103KA88D"
			(at 106.68 128.27 0)
			(effects
				(font
					(size 1.27 1.27)
					(thickness 0.15)
				)
				(justify left bottom)
				(hide yes)
			)
		)
		(property "Manufacturer" "Murata"
			(at 109.22 128.27 0)
			(effects
				(font
					(size 1.27 1.27)
					(thickness 0.15)
				)
				(justify left bottom)
				(hide yes)
			)
		)
		(property "License" "Apache-2.0"
			(at 111.76 128.27 0)
			(effects
				(font
					(size 1.27 1.27)
					(thickness 0.15)
				)
				(justify left bottom)
				(hide yes)
			)
		)
		(property "Author" "Antmicro"
			(at 114.3 128.27 0)
			(effects
				(font
					(size 1.27 1.27)
					(thickness 0.15)
				)
				(justify left bottom)
				(hide yes)
			)
		)
		(property "Val" "10n"
			(at 89.535 147.955 90)
			(effects
				(font
					(size 1.27 1.27)
					(thickness 0.15)
				)
				(justify right)
			)
		)
		(property "Voltage" "50V"
			(at 116.84 128.27 0)
			(effects
				(font
					(size 1.27 1.27)
				)
				(justify left bottom)
				(hide yes)
			)
		)
		(property "Dielectric" "X7R"
			(at 119.38 128.27 0)
			(effects
				(font
					(size 1.27 1.27)
				)
				(justify left bottom)
				(hide yes)
			)
		)
		(pin "1"
		)
		(pin "2"
		)
		(instances
			(project "gmsl-deserializer"
				(path ""
					(reference "C13")
					(unit 1)
				)
			)
		)
	)
	(symbol
		(lib_id "antmicropower:+5V")
		(at 388.62 128.27 0)
		(unit 1)
		(exclude_from_sim no)
		(in_bom yes)
		(on_board yes)
		(dnp no)
		(property "Reference" "#PWR0130"
			(at 403.86 130.81 0)
			(effects
				(font
					(size 1.27 1.27)
					(thickness 0.15)
				)
				(justify left bottom)
				(hide yes)
			)
		)
		(property "Value" "+5V"
			(at 388.62 124.46 0)
			(effects
				(font
					(size 1.27 1.27)
					(thickness 0.15)
				)
			)
		)
		(property "Footprint" ""
			(at 403.86 135.89 0)
			(effects
				(font
					(size 1.27 1.27)
					(thickness 0.15)
				)
				(justify left bottom)
				(hide yes)
			)
		)
		(property "Datasheet" ""
			(at 403.86 138.43 0)
			(effects
				(font
					(size 1.27 1.27)
					(thickness 0.15)
				)
				(justify left bottom)
				(hide yes)
			)
		)
		(property "Description" ""
			(at 388.62 128.27 0)
			(effects
				(font
					(size 1.27 1.27)
				)
				(hide yes)
			)
		)
		(property "Author" "Antmicro"
			(at 403.86 135.89 0)
			(effects
				(font
					(size 1.27 1.27)
					(thickness 0.15)
				)
				(justify left bottom)
				(hide yes)
			)
		)
		(property "License" "Apache-2.0"
			(at 403.86 138.43 0)
			(effects
				(font
					(size 1.27 1.27)
					(thickness 0.15)
				)
				(justify left bottom)
				(hide yes)
			)
		)
		(pin "1"
		)
		(instances
			(project "gmsl-deserializer"
				(path ""
					(reference "#PWR0130")
					(unit 1)
				)
			)
		)
	)
	(symbol
		(lib_id "antmicroLEDIndicationDiscrete:LED_G_0603_LTST-C190GKT")
		(at 168.91 241.3 270)
		(mirror x)
		(unit 1)
		(exclude_from_sim no)
		(in_bom yes)
		(on_board yes)
		(dnp no)
		(property "Reference" "D16"
			(at 167.64 237.49 90)
			(effects
				(font
					(size 1.27 1.27)
					(thickness 0.15)
				)
				(justify right)
			)
		)
		(property "Value" "LED_G_0603_LTST-C190GKT"
			(at 140.335 236.22 90)
			(effects
				(font
					(size 1.27 1.27)
					(thickness 0.15)
				)
				(justify left)
				(hide yes)
			)
		)
		(property "Footprint" "antmicro-footprints:LED_0603_1608Metric_G"
			(at 158.75 218.44 0)
			(effects
				(font
					(size 1.27 1.27)
					(thickness 0.15)
				)
				(justify left bottom)
				(hide yes)
			)
		)
		(property "Datasheet" "https://media.digikey.com/pdf/Data%20Sheets/Lite-On%20PDFs/LTST-C190GKT.pdf"
			(at 156.21 218.44 0)
			(effects
				(font
					(size 1.27 1.27)
					(thickness 0.15)
				)
				(justify left bottom)
				(hide yes)
			)
		)
		(property "Description" "LED, Green, SMD, 0603, 20 mA, 2.1 V, 569 nm"
			(at 168.91 241.3 0)
			(effects
				(font
					(size 1.27 1.27)
				)
				(hide yes)
			)
		)
		(property "MPN" "LTST-C190GKT"
			(at 167.64 238.76 90)
			(effects
				(font
					(size 1.27 1.27)
					(thickness 0.15)
				)
				(justify right bottom)
			)
		)
		(property "Manufacturer" "Lite-On"
			(at 151.13 218.44 0)
			(effects
				(font
					(size 1.27 1.27)
					(thickness 0.15)
				)
				(justify left bottom)
				(hide yes)
			)
		)
		(property "Author" "Antmicro"
			(at 148.59 218.44 0)
			(effects
				(font
					(size 1.27 1.27)
					(thickness 0.15)
				)
				(justify left bottom)
				(hide yes)
			)
		)
		(property "License" "Apache-2.0"
			(at 146.05 218.44 0)
			(effects
				(font
					(size 1.27 1.27)
					(thickness 0.15)
				)
				(justify left bottom)
				(hide yes)
			)
		)
		(property "VSD_class" "LED"
			(at 143.51 218.44 0)
			(effects
				(font
					(size 1.27 1.27)
				)
				(justify left bottom)
				(hide yes)
			)
		)
		(property "Color" "Green"
			(at 163.83 218.44 0)
			(effects
				(font
					(size 1.27 1.27)
				)
				(justify left bottom)
				(hide yes)
			)
		)
		(pin "1"
		)
		(pin "2"
		)
		(instances
			(project "gmsl-deserializer"
				(path ""
					(reference "D16")
					(unit 1)
				)
			)
		)
	)
	(symbol
		(lib_id "antmicropower:GND")
		(at 387.35 226.06 0)
		(unit 1)
		(exclude_from_sim no)
		(in_bom yes)
		(on_board yes)
		(dnp no)
		(property "Reference" "#PWR064"
			(at 396.24 228.6 0)
			(effects
				(font
					(size 1.27 1.27)
					(thickness 0.15)
				)
				(justify left bottom)
				(hide yes)
			)
		)
		(property "Value" "GND"
			(at 387.35 229.87 0)
			(effects
				(font
					(size 1.27 1.27)
					(thickness 0.15)
				)
			)
		)
		(property "Footprint" ""
			(at 396.24 233.68 0)
			(effects
				(font
					(size 1.27 1.27)
					(thickness 0.15)
				)
				(justify left bottom)
				(hide yes)
			)
		)
		(property "Datasheet" ""
			(at 396.24 238.76 0)
			(effects
				(font
					(size 1.27 1.27)
					(thickness 0.15)
				)
				(justify left bottom)
				(hide yes)
			)
		)
		(property "Description" ""
			(at 387.35 226.06 0)
			(effects
				(font
					(size 1.27 1.27)
				)
				(hide yes)
			)
		)
		(property "Author" "Antmicro"
			(at 396.24 233.68 0)
			(effects
				(font
					(size 1.27 1.27)
					(thickness 0.15)
				)
				(justify left bottom)
				(hide yes)
			)
		)
		(property "License" "Apache-2.0"
			(at 396.24 236.22 0)
			(effects
				(font
					(size 1.27 1.27)
					(thickness 0.15)
				)
				(justify left bottom)
				(hide yes)
			)
		)
		(pin "1"
		)
		(instances
			(project "gmsl-deserializer"
				(path ""
					(reference "#PWR064")
					(unit 1)
				)
			)
		)
	)
	(symbol
		(lib_id "antmicroCapacitors0402:C_220p_0402")
		(at 222.25 242.57 0)
		(unit 1)
		(exclude_from_sim no)
		(in_bom yes)
		(on_board yes)
		(dnp no)
		(property "Reference" "C15"
			(at 222.25 240.665 0)
			(effects
				(font
					(size 1.27 1.27)
					(thickness 0.15)
				)
			)
		)
		(property "Value" "C_220p_0402"
			(at 242.57 252.73 0)
			(effects
				(font
					(size 1.27 1.27)
					(thickness 0.15)
				)
				(justify left bottom)
				(hide yes)
			)
		)
		(property "Footprint" "antmicro-footprints:C_0402_1005Metric"
			(at 242.57 255.27 0)
			(effects
				(font
					(size 1.27 1.27)
					(thickness 0.15)
				)
				(justify left bottom)
				(hide yes)
			)
		)
		(property "Datasheet" "https://spicat.kyocera-avx.com/product/mlcc/chartview/04025C221JAT2A/"
			(at 242.57 257.81 0)
			(effects
				(font
					(size 1.27 1.27)
					(thickness 0.15)
				)
				(justify left bottom)
				(hide yes)
			)
		)
		(property "Description" "SMD Multilayer Ceramic Capacitor, 220 pF, 50 V, 0402 [1005 Metric], ± 10%, X7R, MC"
			(at 222.25 242.57 0)
			(effects
				(font
					(size 1.27 1.27)
				)
				(hide yes)
			)
		)
		(property "MPN" "04025C221JAT2A"
			(at 242.57 260.35 0)
			(effects
				(font
					(size 1.27 1.27)
					(thickness 0.15)
				)
				(justify left bottom)
				(hide yes)
			)
		)
		(property "Manufacturer" "KYOCERA AVX"
			(at 242.57 262.89 0)
			(effects
				(font
					(size 1.27 1.27)
					(thickness 0.15)
				)
				(justify left bottom)
				(hide yes)
			)
		)
		(property "License" "Apache-2.0"
			(at 242.57 265.43 0)
			(effects
				(font
					(size 1.27 1.27)
					(thickness 0.15)
				)
				(justify left bottom)
				(hide yes)
			)
		)
		(property "Author" "Antmicro"
			(at 242.57 267.97 0)
			(effects
				(font
					(size 1.27 1.27)
					(thickness 0.15)
				)
				(justify left bottom)
				(hide yes)
			)
		)
		(property "Val" "220p"
			(at 228.6 240.665 0)
			(effects
				(font
					(size 1.27 1.27)
					(thickness 0.15)
				)
			)
		)
		(property "Voltage" ""
			(at 242.57 270.51 0)
			(effects
				(font
					(size 1.27 1.27)
				)
				(justify left bottom)
				(hide yes)
			)
		)
		(property "Dielectric" ""
			(at 242.57 273.05 0)
			(effects
				(font
					(size 1.27 1.27)
				)
				(justify left bottom)
				(hide yes)
			)
		)
		(pin "1"
		)
		(pin "2"
		)
		(instances
			(project "gmsl-deserializer"
				(path ""
					(reference "C15")
					(unit 1)
				)
			)
		)
	)
	(symbol
		(lib_id "antmicroResistors0402:R_10k_0402")
		(at 279.4 128.27 90)
		(unit 1)
		(exclude_from_sim no)
		(in_bom yes)
		(on_board yes)
		(dnp no)
		(fields_autoplaced yes)
		(property "Reference" "R31"
			(at 281.305 124.4599 90)
			(effects
				(font
					(size 1.27 1.27)
					(thickness 0.15)
				)
				(justify right)
			)
		)
		(property "Value" "R_10k_0402"
			(at 292.1 107.95 0)
			(effects
				(font
					(size 1.27 1.27)
					(thickness 0.15)
				)
				(justify left bottom)
				(hide yes)
			)
		)
		(property "Footprint" "antmicro-footprints:R_0402_1005Metric"
			(at 294.64 107.95 0)
			(effects
				(font
					(size 1.27 1.27)
					(thickness 0.15)
				)
				(justify left bottom)
				(hide yes)
			)
		)
		(property "Datasheet" "https://www.bourns.com/docs/product-datasheets/cr.pdf"
			(at 297.18 107.95 0)
			(effects
				(font
					(size 1.27 1.27)
					(thickness 0.15)
				)
				(justify left bottom)
				(hide yes)
			)
		)
		(property "Description" "SMD Chip Resistor, 10 kohm, ± 1%, 62.5 mW, 0402 [1005 Metric], Thick Film, General Purpose"
			(at 279.4 128.27 0)
			(effects
				(font
					(size 1.27 1.27)
				)
				(hide yes)
			)
		)
		(property "MPN" "CR0402-FX-1002GLF"
			(at 299.72 107.95 0)
			(effects
				(font
					(size 1.27 1.27)
					(thickness 0.15)
				)
				(justify left bottom)
				(hide yes)
			)
		)
		(property "Manufacturer" "Bourns"
			(at 302.26 107.95 0)
			(effects
				(font
					(size 1.27 1.27)
					(thickness 0.15)
				)
				(justify left bottom)
				(hide yes)
			)
		)
		(property "License" "Apache-2.0"
			(at 304.8 107.95 0)
			(effects
				(font
					(size 1.27 1.27)
					(thickness 0.15)
				)
				(justify left bottom)
				(hide yes)
			)
		)
		(property "Author" "Antmicro"
			(at 307.34 107.95 0)
			(effects
				(font
					(size 1.27 1.27)
					(thickness 0.15)
				)
				(justify left bottom)
				(hide yes)
			)
		)
		(property "Val" "10k"
			(at 281.305 126.9999 90)
			(effects
				(font
					(size 1.27 1.27)
					(thickness 0.15)
				)
				(justify right)
			)
		)
		(property "Tolerance" "1%"
			(at 289.56 107.95 0)
			(effects
				(font
					(size 1.27 1.27)
				)
				(justify left bottom)
				(hide yes)
			)
		)
		(pin "1"
		)
		(pin "2"
		)
		(instances
			(project "gmsl-deserializer"
				(path ""
					(reference "R31")
					(unit 1)
				)
			)
		)
	)
	(symbol
		(lib_id "antmicroTestPoints:TP_0.75mm_SMD")
		(at 62.23 223.52 90)
		(unit 1)
		(exclude_from_sim no)
		(in_bom yes)
		(on_board yes)
		(dnp no)
		(property "Reference" "TP9"
			(at 60.96 218.44 90)
			(effects
				(font
					(size 1.27 1.27)
					(thickness 0.15)
				)
				(justify right)
			)
		)
		(property "Value" "TP_0.75mm_SMD"
			(at 66.04 212.725 0)
			(effects
				(font
					(size 1.27 1.27)
					(thickness 0.15)
				)
				(justify left bottom)
				(hide yes)
			)
		)
		(property "Footprint" "antmicro-footprints:TP_SMD_0.75mm"
			(at 68.58 212.725 0)
			(effects
				(font
					(size 1.27 1.27)
					(thickness 0.15)
				)
				(justify left bottom)
				(hide yes)
			)
		)
		(property "Datasheet" ""
			(at 74.93 205.74 0)
			(effects
				(font
					(size 1.27 1.27)
					(thickness 0.15)
				)
				(justify left bottom)
				(hide yes)
			)
		)
		(property "Description" "SMT test point"
			(at 62.23 223.52 0)
			(effects
				(font
					(size 1.27 1.27)
				)
				(hide yes)
			)
		)
		(property "MPN" ""
			(at 73.66 212.725 0)
			(effects
				(font
					(size 1.27 1.27)
					(thickness 0.15)
				)
				(justify left bottom)
				(hide yes)
			)
		)
		(property "Manufacturer" ""
			(at 68.58 212.725 0)
			(effects
				(font
					(size 1.27 1.27)
					(thickness 0.15)
				)
				(justify left bottom)
				(hide yes)
			)
		)
		(property "Author" "Antmicro"
			(at 71.12 212.725 0)
			(effects
				(font
					(size 1.27 1.27)
					(thickness 0.15)
				)
				(justify left bottom)
				(hide yes)
			)
		)
		(property "License" "Apache-2.0"
			(at 73.66 212.725 0)
			(effects
				(font
					(size 1.27 1.27)
					(thickness 0.15)
				)
				(justify left bottom)
				(hide yes)
			)
		)
		(pin "1"
		)
		(instances
			(project "gmsl-deserializer"
				(path ""
					(reference "TP9")
					(unit 1)
				)
			)
		)
	)
	(symbol
		(lib_id "antmicropower:+12V")
		(at 81.28 60.96 0)
		(unit 1)
		(exclude_from_sim no)
		(in_bom yes)
		(on_board yes)
		(dnp no)
		(fields_autoplaced yes)
		(property "Reference" "#PWR022"
			(at 81.28 64.77 0)
			(effects
				(font
					(size 1.27 1.27)
				)
				(hide yes)
			)
		)
		(property "Value" "+12V"
			(at 81.28 55.88 0)
			(effects
				(font
					(size 1.27 1.27)
				)
			)
		)
		(property "Footprint" ""
			(at 81.28 60.96 0)
			(effects
				(font
					(size 1.27 1.27)
				)
				(hide yes)
			)
		)
		(property "Datasheet" ""
			(at 81.28 60.96 0)
			(effects
				(font
					(size 1.27 1.27)
				)
				(hide yes)
			)
		)
		(property "Description" ""
			(at 81.28 60.96 0)
			(effects
				(font
					(size 1.27 1.27)
				)
				(hide yes)
			)
		)
		(pin "1"
		)
		(instances
			(project "gmsl-deserializer"
				(path ""
					(reference "#PWR022")
					(unit 1)
				)
			)
		)
	)
	(symbol
		(lib_id "antmicroCapacitors0402:C_100n_0402")
		(at 311.15 60.96 0)
		(unit 1)
		(exclude_from_sim no)
		(in_bom yes)
		(on_board yes)
		(dnp no)
		(property "Reference" "C19"
			(at 316.23 59.69 0)
			(effects
				(font
					(size 1.27 1.27)
					(thickness 0.15)
				)
			)
		)
		(property "Value" "C_100n_0402"
			(at 331.47 71.12 0)
			(effects
				(font
					(size 1.27 1.27)
					(thickness 0.15)
				)
				(justify left bottom)
				(hide yes)
			)
		)
		(property "Footprint" "antmicro-footprints:C_0402_1005Metric"
			(at 331.47 73.66 0)
			(effects
				(font
					(size 1.27 1.27)
					(thickness 0.15)
				)
				(justify left bottom)
				(hide yes)
			)
		)
		(property "Datasheet" "https://www.murata.com/products/productdetail?partno=GRM155R61H104KE14%23"
			(at 331.47 76.2 0)
			(effects
				(font
					(size 1.27 1.27)
					(thickness 0.15)
				)
				(justify left bottom)
				(hide yes)
			)
		)
		(property "Description" "SMD Multilayer Ceramic Capacitor, 0.1 µF, 50 V, 0402 [1005 Metric], ± 10%, X5R, GRM Series"
			(at 311.15 60.96 0)
			(effects
				(font
					(size 1.27 1.27)
				)
				(hide yes)
			)
		)
		(property "MPN" "GRM155R61H104KE14D"
			(at 331.47 78.74 0)
			(effects
				(font
					(size 1.27 1.27)
					(thickness 0.15)
				)
				(justify left bottom)
				(hide yes)
			)
		)
		(property "Manufacturer" "Murata"
			(at 331.47 81.28 0)
			(effects
				(font
					(size 1.27 1.27)
					(thickness 0.15)
				)
				(justify left bottom)
				(hide yes)
			)
		)
		(property "License" "Apache-2.0"
			(at 331.47 83.82 0)
			(effects
				(font
					(size 1.27 1.27)
					(thickness 0.15)
				)
				(justify left bottom)
				(hide yes)
			)
		)
		(property "Author" "Antmicro"
			(at 331.47 86.36 0)
			(effects
				(font
					(size 1.27 1.27)
					(thickness 0.15)
				)
				(justify left bottom)
				(hide yes)
			)
		)
		(property "Val" "100n"
			(at 317.5 62.23 0)
			(effects
				(font
					(size 1.27 1.27)
					(thickness 0.15)
				)
			)
		)
		(property "Voltage" "50V"
			(at 331.47 88.9 0)
			(effects
				(font
					(size 1.27 1.27)
				)
				(justify left bottom)
				(hide yes)
			)
		)
		(property "Dielectric" "X5R"
			(at 331.47 91.44 0)
			(effects
				(font
					(size 1.27 1.27)
				)
				(justify left bottom)
				(hide yes)
			)
		)
		(pin "1"
		)
		(pin "2"
		)
		(instances
			(project "gmsl-deserializer"
				(path ""
					(reference "C19")
					(unit 1)
				)
			)
		)
	)
	(symbol
		(lib_id "antmicroTestPoints:TP_0.75mm_SMD")
		(at 250.19 231.14 90)
		(unit 1)
		(exclude_from_sim no)
		(in_bom yes)
		(on_board yes)
		(dnp no)
		(property "Reference" "TP12"
			(at 248.92 226.06 90)
			(effects
				(font
					(size 1.27 1.27)
					(thickness 0.15)
				)
				(justify right)
			)
		)
		(property "Value" "TP_0.75mm_SMD"
			(at 254 220.345 0)
			(effects
				(font
					(size 1.27 1.27)
					(thickness 0.15)
				)
				(justify left bottom)
				(hide yes)
			)
		)
		(property "Footprint" "antmicro-footprints:TP_SMD_0.75mm"
			(at 256.54 220.345 0)
			(effects
				(font
					(size 1.27 1.27)
					(thickness 0.15)
				)
				(justify left bottom)
				(hide yes)
			)
		)
		(property "Datasheet" ""
			(at 262.89 213.36 0)
			(effects
				(font
					(size 1.27 1.27)
					(thickness 0.15)
				)
				(justify left bottom)
				(hide yes)
			)
		)
		(property "Description" "SMT test point"
			(at 250.19 231.14 0)
			(effects
				(font
					(size 1.27 1.27)
				)
				(hide yes)
			)
		)
		(property "MPN" ""
			(at 261.62 220.345 0)
			(effects
				(font
					(size 1.27 1.27)
					(thickness 0.15)
				)
				(justify left bottom)
				(hide yes)
			)
		)
		(property "Manufacturer" ""
			(at 256.54 220.345 0)
			(effects
				(font
					(size 1.27 1.27)
					(thickness 0.15)
				)
				(justify left bottom)
				(hide yes)
			)
		)
		(property "Author" "Antmicro"
			(at 259.08 220.345 0)
			(effects
				(font
					(size 1.27 1.27)
					(thickness 0.15)
				)
				(justify left bottom)
				(hide yes)
			)
		)
		(property "License" "Apache-2.0"
			(at 261.62 220.345 0)
			(effects
				(font
					(size 1.27 1.27)
					(thickness 0.15)
				)
				(justify left bottom)
				(hide yes)
			)
		)
		(pin "1"
		)
		(instances
			(project "gmsl-deserializer"
				(path ""
					(reference "TP12")
					(unit 1)
				)
			)
		)
	)
	(symbol
		(lib_id "antmicropower:GND")
		(at 279.4 144.78 0)
		(unit 1)
		(exclude_from_sim no)
		(in_bom yes)
		(on_board yes)
		(dnp no)
		(property "Reference" "#PWR0112"
			(at 288.29 147.32 0)
			(effects
				(font
					(size 1.27 1.27)
					(thickness 0.15)
				)
				(justify left bottom)
				(hide yes)
			)
		)
		(property "Value" "GND"
			(at 279.4 148.59 0)
			(effects
				(font
					(size 1.27 1.27)
					(thickness 0.15)
				)
			)
		)
		(property "Footprint" ""
			(at 288.29 152.4 0)
			(effects
				(font
					(size 1.27 1.27)
					(thickness 0.15)
				)
				(justify left bottom)
				(hide yes)
			)
		)
		(property "Datasheet" ""
			(at 288.29 157.48 0)
			(effects
				(font
					(size 1.27 1.27)
					(thickness 0.15)
				)
				(justify left bottom)
				(hide yes)
			)
		)
		(property "Description" ""
			(at 279.4 144.78 0)
			(effects
				(font
					(size 1.27 1.27)
				)
				(hide yes)
			)
		)
		(property "Author" "Antmicro"
			(at 288.29 152.4 0)
			(effects
				(font
					(size 1.27 1.27)
					(thickness 0.15)
				)
				(justify left bottom)
				(hide yes)
			)
		)
		(property "License" "Apache-2.0"
			(at 288.29 154.94 0)
			(effects
				(font
					(size 1.27 1.27)
					(thickness 0.15)
				)
				(justify left bottom)
				(hide yes)
			)
		)
		(pin "1"
		)
		(instances
			(project "gmsl-deserializer"
				(path ""
					(reference "#PWR0112")
					(unit 1)
				)
			)
		)
	)
	(symbol
		(lib_id "antmicroFixedInductors:L_470n_1A_Coilcraft-PFL1609")
		(at 157.48 114.3 0)
		(unit 1)
		(exclude_from_sim no)
		(in_bom yes)
		(on_board yes)
		(dnp no)
		(fields_autoplaced yes)
		(property "Reference" "L15"
			(at 160.02 109.22 0)
			(effects
				(font
					(size 1.27 1.27)
					(thickness 0.15)
				)
			)
		)
		(property "Value" "L_470n_1A_Coilcraft-PFL1609"
			(at 171.45 116.84 0)
			(effects
				(font
					(size 1.27 1.27)
					(thickness 0.15)
				)
				(justify left bottom)
				(hide yes)
			)
		)
		(property "Footprint" "antmicro-footprints:L_Coilcraft-PFL1609"
			(at 171.45 121.92 0)
			(effects
				(font
					(size 1.27 1.27)
					(thickness 0.15)
				)
				(justify left bottom)
				(hide yes)
			)
		)
		(property "Datasheet" "https://www.coilcraft.com/getmedia/2f4cd442-d64d-4413-a518-12fcfd03318d/pfl1609.pdf"
			(at 171.45 124.46 0)
			(effects
				(font
					(size 1.27 1.27)
					(thickness 0.15)
				)
				(justify left bottom)
				(hide yes)
			)
		)
		(property "Description" "Power Inductor (SMT), 6.8 µH, 9.2 A, Shielded, 12.8 A, XAL7070"
			(at 157.48 114.3 0)
			(effects
				(font
					(size 1.27 1.27)
				)
				(hide yes)
			)
		)
		(property "Val" "470n/0.99A"
			(at 160.02 111.76 0)
			(effects
				(font
					(size 1.27 1.27)
					(thickness 0.15)
				)
			)
		)
		(property "Manufacturer" "Coilcraft"
			(at 171.45 127 0)
			(effects
				(font
					(size 1.27 1.27)
					(thickness 0.15)
				)
				(justify left bottom)
				(hide yes)
			)
		)
		(property "MPN" "PFL1609-471"
			(at 171.45 129.54 0)
			(effects
				(font
					(size 1.27 1.27)
					(thickness 0.15)
				)
				(justify left bottom)
				(hide yes)
			)
		)
		(property "ISat" "0.99 A"
			(at 171.45 130.81 0)
			(effects
				(font
					(size 1.27 1.27)
				)
				(justify left)
				(hide yes)
			)
		)
		(property "IMax" "1 A"
			(at 171.45 134.62 0)
			(effects
				(font
					(size 1.27 1.27)
					(thickness 0.15)
				)
				(justify left bottom)
				(hide yes)
			)
		)
		(property "Size" "1.07x1.8"
			(at 171.45 137.16 0)
			(effects
				(font
					(size 1.27 1.27)
					(thickness 0.15)
				)
				(justify left bottom)
				(hide yes)
			)
		)
		(property "Author" "Antmicro"
			(at 171.45 139.7 0)
			(effects
				(font
					(size 1.27 1.27)
					(thickness 0.15)
				)
				(justify left bottom)
				(hide yes)
			)
		)
		(property "License" "Apache-2.0"
			(at 171.45 142.24 0)
			(effects
				(font
					(size 1.27 1.27)
					(thickness 0.15)
				)
				(justify left bottom)
				(hide yes)
			)
		)
		(pin "1"
		)
		(pin "2"
		)
		(instances
			(project "gmsl-deserializer"
				(path ""
					(reference "L15")
					(unit 1)
				)
			)
		)
	)
	(symbol
		(lib_id "antmicroCapacitors0402:C_10n_0402")
		(at 88.9 71.12 90)
		(unit 1)
		(exclude_from_sim no)
		(in_bom yes)
		(on_board yes)
		(dnp no)
		(property "Reference" "C10"
			(at 89.535 66.675 90)
			(effects
				(font
					(size 1.27 1.27)
					(thickness 0.15)
				)
				(justify right)
			)
		)
		(property "Value" "C_10n_0402"
			(at 99.06 50.8 0)
			(effects
				(font
					(size 1.27 1.27)
					(thickness 0.15)
				)
				(justify left bottom)
				(hide yes)
			)
		)
		(property "Footprint" "antmicro-footprints:C_0402_1005Metric"
			(at 101.6 50.8 0)
			(effects
				(font
					(size 1.27 1.27)
					(thickness 0.15)
				)
				(justify left bottom)
				(hide yes)
			)
		)
		(property "Datasheet" "https://www.murata.com/products/productdetail?partno=GRM155R71H103KA88%23"
			(at 104.14 50.8 0)
			(effects
				(font
					(size 1.27 1.27)
					(thickness 0.15)
				)
				(justify left bottom)
				(hide yes)
			)
		)
		(property "Description" "SMD Multilayer Ceramic Capacitor, 10000 pF, 50 V, 0402 [1005 Metric], ± 10%, X7R, GRM Series"
			(at 88.9 71.12 0)
			(effects
				(font
					(size 1.27 1.27)
				)
				(hide yes)
			)
		)
		(property "MPN" "GRM155R71H103KA88D"
			(at 106.68 50.8 0)
			(effects
				(font
					(size 1.27 1.27)
					(thickness 0.15)
				)
				(justify left bottom)
				(hide yes)
			)
		)
		(property "Manufacturer" "Murata"
			(at 109.22 50.8 0)
			(effects
				(font
					(size 1.27 1.27)
					(thickness 0.15)
				)
				(justify left bottom)
				(hide yes)
			)
		)
		(property "License" "Apache-2.0"
			(at 111.76 50.8 0)
			(effects
				(font
					(size 1.27 1.27)
					(thickness 0.15)
				)
				(justify left bottom)
				(hide yes)
			)
		)
		(property "Author" "Antmicro"
			(at 114.3 50.8 0)
			(effects
				(font
					(size 1.27 1.27)
					(thickness 0.15)
				)
				(justify left bottom)
				(hide yes)
			)
		)
		(property "Val" "10n"
			(at 89.535 70.485 90)
			(effects
				(font
					(size 1.27 1.27)
					(thickness 0.15)
				)
				(justify right)
			)
		)
		(property "Voltage" "50V"
			(at 116.84 50.8 0)
			(effects
				(font
					(size 1.27 1.27)
				)
				(justify left bottom)
				(hide yes)
			)
		)
		(property "Dielectric" "X7R"
			(at 119.38 50.8 0)
			(effects
				(font
					(size 1.27 1.27)
				)
				(justify left bottom)
				(hide yes)
			)
		)
		(pin "1"
		)
		(pin "2"
		)
		(instances
			(project "gmsl-deserializer"
				(path ""
					(reference "C10")
					(unit 1)
				)
			)
		)
	)
	(symbol
		(lib_id "antmicroResistors0402:R_12k4_0402")
		(at 327.66 62.23 90)
		(unit 1)
		(exclude_from_sim no)
		(in_bom yes)
		(on_board yes)
		(dnp no)
		(fields_autoplaced yes)
		(property "Reference" "R35"
			(at 329.565 58.4199 90)
			(effects
				(font
					(size 1.27 1.27)
					(thickness 0.15)
				)
				(justify right)
			)
		)
		(property "Value" "R_12k4_0402"
			(at 340.36 41.91 0)
			(effects
				(font
					(size 1.27 1.27)
					(thickness 0.15)
				)
				(justify left bottom)
				(hide yes)
			)
		)
		(property "Footprint" "antmicro-footprints:R_0402_1005Metric"
			(at 342.9 41.91 0)
			(effects
				(font
					(size 1.27 1.27)
					(thickness 0.15)
				)
				(justify left bottom)
				(hide yes)
			)
		)
		(property "Datasheet" "https://www.bourns.com/docs/product-datasheets/cr.pdf"
			(at 345.44 41.91 0)
			(effects
				(font
					(size 1.27 1.27)
					(thickness 0.15)
				)
				(justify left bottom)
				(hide yes)
			)
		)
		(property "Description" "SMD Chip Resistor, 12.4 kohm, ± 1%, 62.5 mW, 0402 [1005 Metric], Thick Film, General Purpose"
			(at 327.66 62.23 0)
			(effects
				(font
					(size 1.27 1.27)
				)
				(hide yes)
			)
		)
		(property "MPN" "CR0402-FX-1242GLF"
			(at 347.98 41.91 0)
			(effects
				(font
					(size 1.27 1.27)
					(thickness 0.15)
				)
				(justify left bottom)
				(hide yes)
			)
		)
		(property "Manufacturer" "Bourns"
			(at 350.52 41.91 0)
			(effects
				(font
					(size 1.27 1.27)
					(thickness 0.15)
				)
				(justify left bottom)
				(hide yes)
			)
		)
		(property "License" "Apache-2.0"
			(at 353.06 41.91 0)
			(effects
				(font
					(size 1.27 1.27)
					(thickness 0.15)
				)
				(justify left bottom)
				(hide yes)
			)
		)
		(property "Author" "Antmicro"
			(at 355.6 41.91 0)
			(effects
				(font
					(size 1.27 1.27)
					(thickness 0.15)
				)
				(justify left bottom)
				(hide yes)
			)
		)
		(property "Val" "12k4"
			(at 329.565 60.9599 90)
			(effects
				(font
					(size 1.27 1.27)
					(thickness 0.15)
				)
				(justify right)
			)
		)
		(property "Tolerance" "1%"
			(at 337.82 41.91 0)
			(effects
				(font
					(size 1.27 1.27)
				)
				(justify left bottom)
				(hide yes)
			)
		)
		(pin "1"
		)
		(pin "2"
		)
		(instances
			(project "gmsl-deserializer"
				(path ""
					(reference "R35")
					(unit 1)
				)
			)
		)
	)
	(symbol
		(lib_id "antmicropower:GND")
		(at 168.91 250.19 0)
		(unit 1)
		(exclude_from_sim no)
		(in_bom yes)
		(on_board yes)
		(dnp no)
		(property "Reference" "#PWR0125"
			(at 177.8 252.73 0)
			(effects
				(font
					(size 1.27 1.27)
					(thickness 0.15)
				)
				(justify left bottom)
				(hide yes)
			)
		)
		(property "Value" "GND"
			(at 168.91 254 0)
			(effects
				(font
					(size 1.27 1.27)
					(thickness 0.15)
				)
			)
		)
		(property "Footprint" ""
			(at 177.8 257.81 0)
			(effects
				(font
					(size 1.27 1.27)
					(thickness 0.15)
				)
				(justify left bottom)
				(hide yes)
			)
		)
		(property "Datasheet" ""
			(at 177.8 262.89 0)
			(effects
				(font
					(size 1.27 1.27)
					(thickness 0.15)
				)
				(justify left bottom)
				(hide yes)
			)
		)
		(property "Description" ""
			(at 168.91 250.19 0)
			(effects
				(font
					(size 1.27 1.27)
				)
				(hide yes)
			)
		)
		(property "Author" "Antmicro"
			(at 177.8 257.81 0)
			(effects
				(font
					(size 1.27 1.27)
					(thickness 0.15)
				)
				(justify left bottom)
				(hide yes)
			)
		)
		(property "License" "Apache-2.0"
			(at 177.8 260.35 0)
			(effects
				(font
					(size 1.27 1.27)
					(thickness 0.15)
				)
				(justify left bottom)
				(hide yes)
			)
		)
		(pin "1"
		)
		(instances
			(project "gmsl-deserializer"
				(path ""
					(reference "#PWR0125")
					(unit 1)
				)
			)
		)
	)
	(symbol
		(lib_id "antmicroResistors0402:R_5k1_0402")
		(at 104.14 97.79 0)
		(unit 1)
		(exclude_from_sim no)
		(in_bom yes)
		(on_board yes)
		(dnp no)
		(fields_autoplaced yes)
		(property "Reference" "R20"
			(at 106.68 92.075 0)
			(effects
				(font
					(size 1.27 1.27)
					(thickness 0.15)
				)
			)
		)
		(property "Value" "R_5k1_0402"
			(at 124.46 110.49 0)
			(effects
				(font
					(size 1.27 1.27)
					(thickness 0.15)
				)
				(justify left bottom)
				(hide yes)
			)
		)
		(property "Footprint" "antmicro-footprints:R_0402_1005Metric"
			(at 124.46 113.03 0)
			(effects
				(font
					(size 1.27 1.27)
					(thickness 0.15)
				)
				(justify left bottom)
				(hide yes)
			)
		)
		(property "Datasheet" "https://www.bourns.com/docs/product-datasheets/cr.pdf"
			(at 124.46 115.57 0)
			(effects
				(font
					(size 1.27 1.27)
					(thickness 0.15)
				)
				(justify left bottom)
				(hide yes)
			)
		)
		(property "Description" "SMD Chip Resistor, 5.1 kohm, ± 1%, 63 mW, 0402 [1005 Metric], Thick Film, General Purpose"
			(at 104.14 97.79 0)
			(effects
				(font
					(size 1.27 1.27)
				)
				(hide yes)
			)
		)
		(property "MPN" "CR0402-FX-5101GLF"
			(at 124.46 118.11 0)
			(effects
				(font
					(size 1.27 1.27)
					(thickness 0.15)
				)
				(justify left bottom)
				(hide yes)
			)
		)
		(property "Manufacturer" "Bourns"
			(at 124.46 120.65 0)
			(effects
				(font
					(size 1.27 1.27)
					(thickness 0.15)
				)
				(justify left bottom)
				(hide yes)
			)
		)
		(property "License" "Apache-2.0"
			(at 124.46 123.19 0)
			(effects
				(font
					(size 1.27 1.27)
					(thickness 0.15)
				)
				(justify left bottom)
				(hide yes)
			)
		)
		(property "Author" "Antmicro"
			(at 124.46 125.73 0)
			(effects
				(font
					(size 1.27 1.27)
					(thickness 0.15)
				)
				(justify left bottom)
				(hide yes)
			)
		)
		(property "Val" "5k1"
			(at 106.68 94.615 0)
			(effects
				(font
					(size 1.27 1.27)
					(thickness 0.15)
				)
			)
		)
		(property "Tolerance" "1%"
			(at 124.46 107.95 0)
			(effects
				(font
					(size 1.27 1.27)
				)
				(justify left bottom)
				(hide yes)
			)
		)
		(pin "1"
		)
		(pin "2"
		)
		(instances
			(project "gmsl-deserializer"
				(path ""
					(reference "R20")
					(unit 1)
				)
			)
		)
	)
	(symbol
		(lib_id "antmicroLEDIndicationDiscrete:LED_G_0603_LTST-C190GKT")
		(at 31.75 236.22 270)
		(mirror x)
		(unit 1)
		(exclude_from_sim no)
		(in_bom yes)
		(on_board yes)
		(dnp no)
		(property "Reference" "D15"
			(at 35.56 232.41 90)
			(effects
				(font
					(size 1.27 1.27)
					(thickness 0.15)
				)
				(justify left)
			)
		)
		(property "Value" "LED_G_0603_LTST-C190GKT"
			(at 3.175 231.14 90)
			(effects
				(font
					(size 1.27 1.27)
					(thickness 0.15)
				)
				(justify left)
				(hide yes)
			)
		)
		(property "Footprint" "antmicro-footprints:LED_0603_1608Metric_G"
			(at 21.59 213.36 0)
			(effects
				(font
					(size 1.27 1.27)
					(thickness 0.15)
				)
				(justify left bottom)
				(hide yes)
			)
		)
		(property "Datasheet" "https://media.digikey.com/pdf/Data%20Sheets/Lite-On%20PDFs/LTST-C190GKT.pdf"
			(at 19.05 213.36 0)
			(effects
				(font
					(size 1.27 1.27)
					(thickness 0.15)
				)
				(justify left bottom)
				(hide yes)
			)
		)
		(property "Description" "LED, Green, SMD, 0603, 20 mA, 2.1 V, 569 nm"
			(at 31.75 236.22 0)
			(effects
				(font
					(size 1.27 1.27)
				)
				(hide yes)
			)
		)
		(property "MPN" "LTST-C190GKT"
			(at 35.56 233.68 90)
			(effects
				(font
					(size 1.27 1.27)
					(thickness 0.15)
				)
				(justify left bottom)
			)
		)
		(property "Manufacturer" "Lite-On"
			(at 13.97 213.36 0)
			(effects
				(font
					(size 1.27 1.27)
					(thickness 0.15)
				)
				(justify left bottom)
				(hide yes)
			)
		)
		(property "Author" "Antmicro"
			(at 11.43 213.36 0)
			(effects
				(font
					(size 1.27 1.27)
					(thickness 0.15)
				)
				(justify left bottom)
				(hide yes)
			)
		)
		(property "License" "Apache-2.0"
			(at 8.89 213.36 0)
			(effects
				(font
					(size 1.27 1.27)
					(thickness 0.15)
				)
				(justify left bottom)
				(hide yes)
			)
		)
		(property "VSD_class" "LED"
			(at 6.35 213.36 0)
			(effects
				(font
					(size 1.27 1.27)
				)
				(justify left bottom)
				(hide yes)
			)
		)
		(property "Color" "Green"
			(at 26.67 213.36 0)
			(effects
				(font
					(size 1.27 1.27)
				)
				(justify left bottom)
				(hide yes)
			)
		)
		(pin "1"
		)
		(pin "2"
		)
		(instances
			(project "gmsl-deserializer"
				(path ""
					(reference "D15")
					(unit 1)
				)
			)
		)
	)
	(symbol
		(lib_id "antmicroResistors0402:R_5k1_0402")
		(at 104.14 124.46 0)
		(unit 1)
		(exclude_from_sim no)
		(in_bom yes)
		(on_board yes)
		(dnp no)
		(fields_autoplaced yes)
		(property "Reference" "R21"
			(at 106.68 118.745 0)
			(effects
				(font
					(size 1.27 1.27)
					(thickness 0.15)
				)
			)
		)
		(property "Value" "R_5k1_0402"
			(at 124.46 137.16 0)
			(effects
				(font
					(size 1.27 1.27)
					(thickness 0.15)
				)
				(justify left bottom)
				(hide yes)
			)
		)
		(property "Footprint" "antmicro-footprints:R_0402_1005Metric"
			(at 124.46 139.7 0)
			(effects
				(font
					(size 1.27 1.27)
					(thickness 0.15)
				)
				(justify left bottom)
				(hide yes)
			)
		)
		(property "Datasheet" "https://www.bourns.com/docs/product-datasheets/cr.pdf"
			(at 124.46 142.24 0)
			(effects
				(font
					(size 1.27 1.27)
					(thickness 0.15)
				)
				(justify left bottom)
				(hide yes)
			)
		)
		(property "Description" "SMD Chip Resistor, 5.1 kohm, ± 1%, 63 mW, 0402 [1005 Metric], Thick Film, General Purpose"
			(at 104.14 124.46 0)
			(effects
				(font
					(size 1.27 1.27)
				)
				(hide yes)
			)
		)
		(property "MPN" "CR0402-FX-5101GLF"
			(at 124.46 144.78 0)
			(effects
				(font
					(size 1.27 1.27)
					(thickness 0.15)
				)
				(justify left bottom)
				(hide yes)
			)
		)
		(property "Manufacturer" "Bourns"
			(at 124.46 147.32 0)
			(effects
				(font
					(size 1.27 1.27)
					(thickness 0.15)
				)
				(justify left bottom)
				(hide yes)
			)
		)
		(property "License" "Apache-2.0"
			(at 124.46 149.86 0)
			(effects
				(font
					(size 1.27 1.27)
					(thickness 0.15)
				)
				(justify left bottom)
				(hide yes)
			)
		)
		(property "Author" "Antmicro"
			(at 124.46 152.4 0)
			(effects
				(font
					(size 1.27 1.27)
					(thickness 0.15)
				)
				(justify left bottom)
				(hide yes)
			)
		)
		(property "Val" "5k1"
			(at 106.68 121.285 0)
			(effects
				(font
					(size 1.27 1.27)
					(thickness 0.15)
				)
			)
		)
		(property "Tolerance" "1%"
			(at 124.46 134.62 0)
			(effects
				(font
					(size 1.27 1.27)
				)
				(justify left bottom)
				(hide yes)
			)
		)
		(pin "1"
		)
		(pin "2"
		)
		(instances
			(project "gmsl-deserializer"
				(path ""
					(reference "R21")
					(unit 1)
				)
			)
		)
	)
	(symbol
		(lib_id "antmicropower:+5V")
		(at 394.97 215.9 0)
		(unit 1)
		(exclude_from_sim no)
		(in_bom yes)
		(on_board yes)
		(dnp no)
		(property "Reference" "#PWR063"
			(at 410.21 218.44 0)
			(effects
				(font
					(size 1.27 1.27)
					(thickness 0.15)
				)
				(justify left bottom)
				(hide yes)
			)
		)
		(property "Value" "+5V"
			(at 394.97 212.09 0)
			(effects
				(font
					(size 1.27 1.27)
					(thickness 0.15)
				)
			)
		)
		(property "Footprint" ""
			(at 410.21 223.52 0)
			(effects
				(font
					(size 1.27 1.27)
					(thickness 0.15)
				)
				(justify left bottom)
				(hide yes)
			)
		)
		(property "Datasheet" ""
			(at 410.21 226.06 0)
			(effects
				(font
					(size 1.27 1.27)
					(thickness 0.15)
				)
				(justify left bottom)
				(hide yes)
			)
		)
		(property "Description" ""
			(at 394.97 215.9 0)
			(effects
				(font
					(size 1.27 1.27)
				)
				(hide yes)
			)
		)
		(property "Author" "Antmicro"
			(at 410.21 223.52 0)
			(effects
				(font
					(size 1.27 1.27)
					(thickness 0.15)
				)
				(justify left bottom)
				(hide yes)
			)
		)
		(property "License" "Apache-2.0"
			(at 410.21 226.06 0)
			(effects
				(font
					(size 1.27 1.27)
					(thickness 0.15)
				)
				(justify left bottom)
				(hide yes)
			)
		)
		(pin "1"
		)
		(instances
			(project "gmsl-deserializer"
				(path ""
					(reference "#PWR063")
					(unit 1)
				)
			)
		)
	)
	(symbol
		(lib_id "antmicroDCDCConverters:AP62301_TSOT")
		(at 288.29 55.88 0)
		(unit 1)
		(exclude_from_sim no)
		(in_bom yes)
		(on_board yes)
		(dnp no)
		(fields_autoplaced yes)
		(property "Reference" "U4"
			(at 298.45 47.625 0)
			(effects
				(font
					(size 1.27 1.27)
					(thickness 0.15)
				)
			)
		)
		(property "Value" "AP62301_TSOT"
			(at 323.85 63.5 0)
			(effects
				(font
					(size 1.27 1.27)
					(thickness 0.15)
				)
				(justify left bottom)
				(hide yes)
			)
		)
		(property "Footprint" "antmicro-footprints:TSOT23-6"
			(at 323.85 66.04 0)
			(effects
				(font
					(size 1.27 1.27)
					(thickness 0.15)
				)
				(justify left bottom)
				(hide yes)
			)
		)
		(property "Datasheet" "https://www.diodes.com/assets/Datasheets/AP62300_AP62301_AP62300T.pdf"
			(at 323.85 68.58 0)
			(effects
				(font
					(size 1.27 1.27)
					(thickness 0.15)
				)
				(justify left bottom)
				(hide yes)
			)
		)
		(property "Description" "DC-DC Switching Synchronous Buck Regulator, Adjustable, 4.2V-18Vin, 0.8V-7V/3A out, TSOT-26-6"
			(at 288.29 55.88 0)
			(effects
				(font
					(size 1.27 1.27)
				)
				(hide yes)
			)
		)
		(property "MPN" "AP62301WU-7"
			(at 298.45 50.165 0)
			(effects
				(font
					(size 1.27 1.27)
					(thickness 0.15)
				)
			)
		)
		(property "Manufacturer" "Diodes Incorporated"
			(at 323.85 71.12 0)
			(effects
				(font
					(size 1.27 1.27)
					(thickness 0.15)
				)
				(justify left bottom)
				(hide yes)
			)
		)
		(property "Author" "Antmicro"
			(at 323.85 73.66 0)
			(effects
				(font
					(size 1.27 1.27)
					(thickness 0.15)
				)
				(justify left bottom)
				(hide yes)
			)
		)
		(property "License" "Apache-2.0"
			(at 323.85 76.2 0)
			(effects
				(font
					(size 1.27 1.27)
					(thickness 0.15)
				)
				(justify left bottom)
				(hide yes)
			)
		)
		(pin "1"
		)
		(pin "2"
		)
		(pin "3"
		)
		(pin "4"
		)
		(pin "5"
		)
		(pin "6"
		)
		(instances
			(project "gmsl-deserializer"
				(path ""
					(reference "U4")
					(unit 1)
				)
			)
		)
	)
	(symbol
		(lib_id "antmicroResistors0402:R_6k8_0402")
		(at 387.35 224.79 90)
		(unit 1)
		(exclude_from_sim no)
		(in_bom yes)
		(on_board yes)
		(dnp no)
		(property "Reference" "R42"
			(at 389.255 220.98 90)
			(effects
				(font
					(size 1.27 1.27)
					(thickness 0.15)
				)
				(justify right)
			)
		)
		(property "Value" "R_6k8_0402"
			(at 400.05 204.47 0)
			(effects
				(font
					(size 1.27 1.27)
					(thickness 0.15)
				)
				(justify left bottom)
				(hide yes)
			)
		)
		(property "Footprint" "antmicro-footprints:R_0402_1005Metric"
			(at 402.59 204.47 0)
			(effects
				(font
					(size 1.27 1.27)
					(thickness 0.15)
				)
				(justify left bottom)
				(hide yes)
			)
		)
		(property "Datasheet" "https://www.bourns.com/docs/product-datasheets/cr.pdf"
			(at 405.13 204.47 0)
			(effects
				(font
					(size 1.27 1.27)
					(thickness 0.15)
				)
				(justify left bottom)
				(hide yes)
			)
		)
		(property "Description" "SMD Chip Resistor, 6.8 kohm, ± 1%, 63 mW, 0402 [1005 Metric], Thick Film, General Purpose"
			(at 387.35 224.79 0)
			(effects
				(font
					(size 1.27 1.27)
				)
				(hide yes)
			)
		)
		(property "MPN" "CR0402-FX-6801GLF"
			(at 407.67 204.47 0)
			(effects
				(font
					(size 1.27 1.27)
					(thickness 0.15)
				)
				(justify left bottom)
				(hide yes)
			)
		)
		(property "Manufacturer" "Bourns"
			(at 410.21 204.47 0)
			(effects
				(font
					(size 1.27 1.27)
					(thickness 0.15)
				)
				(justify left bottom)
				(hide yes)
			)
		)
		(property "License" "Apache-2.0"
			(at 412.75 204.47 0)
			(effects
				(font
					(size 1.27 1.27)
					(thickness 0.15)
				)
				(justify left bottom)
				(hide yes)
			)
		)
		(property "Author" "Antmicro"
			(at 415.29 204.47 0)
			(effects
				(font
					(size 1.27 1.27)
					(thickness 0.15)
				)
				(justify left bottom)
				(hide yes)
			)
		)
		(property "Val" "6k8"
			(at 389.255 223.52 90)
			(effects
				(font
					(size 1.27 1.27)
					(thickness 0.15)
				)
				(justify right)
			)
		)
		(property "Tolerance" "1%"
			(at 397.51 204.47 0)
			(effects
				(font
					(size 1.27 1.27)
				)
				(justify left bottom)
				(hide yes)
			)
		)
		(pin "1"
		)
		(pin "2"
		)
		(instances
			(project "gmsl-deserializer"
				(path ""
					(reference "R42")
					(unit 1)
				)
			)
		)
	)
	(symbol
		(lib_id "antmicropower:GND")
		(at 31.75 245.11 0)
		(unit 1)
		(exclude_from_sim no)
		(in_bom yes)
		(on_board yes)
		(dnp no)
		(property "Reference" "#PWR0126"
			(at 40.64 247.65 0)
			(effects
				(font
					(size 1.27 1.27)
					(thickness 0.15)
				)
				(justify left bottom)
				(hide yes)
			)
		)
		(property "Value" "GND"
			(at 31.75 248.92 0)
			(effects
				(font
					(size 1.27 1.27)
					(thickness 0.15)
				)
			)
		)
		(property "Footprint" ""
			(at 40.64 252.73 0)
			(effects
				(font
					(size 1.27 1.27)
					(thickness 0.15)
				)
				(justify left bottom)
				(hide yes)
			)
		)
		(property "Datasheet" ""
			(at 40.64 257.81 0)
			(effects
				(font
					(size 1.27 1.27)
					(thickness 0.15)
				)
				(justify left bottom)
				(hide yes)
			)
		)
		(property "Description" ""
			(at 31.75 245.11 0)
			(effects
				(font
					(size 1.27 1.27)
				)
				(hide yes)
			)
		)
		(property "Author" "Antmicro"
			(at 40.64 252.73 0)
			(effects
				(font
					(size 1.27 1.27)
					(thickness 0.15)
				)
				(justify left bottom)
				(hide yes)
			)
		)
		(property "License" "Apache-2.0"
			(at 40.64 255.27 0)
			(effects
				(font
					(size 1.27 1.27)
					(thickness 0.15)
				)
				(justify left bottom)
				(hide yes)
			)
		)
		(pin "1"
		)
		(instances
			(project "gmsl-deserializer"
				(path ""
					(reference "#PWR0126")
					(unit 1)
				)
			)
		)
	)
	(symbol
		(lib_id "antmicropower:GND")
		(at 81.28 149.86 0)
		(unit 1)
		(exclude_from_sim no)
		(in_bom yes)
		(on_board yes)
		(dnp no)
		(property "Reference" "#PWR029"
			(at 90.17 152.4 0)
			(effects
				(font
					(size 1.27 1.27)
					(thickness 0.15)
				)
				(justify left bottom)
				(hide yes)
			)
		)
		(property "Value" "GND"
			(at 81.28 153.67 0)
			(effects
				(font
					(size 1.27 1.27)
					(thickness 0.15)
				)
			)
		)
		(property "Footprint" ""
			(at 90.17 157.48 0)
			(effects
				(font
					(size 1.27 1.27)
					(thickness 0.15)
				)
				(justify left bottom)
				(hide yes)
			)
		)
		(property "Datasheet" ""
			(at 90.17 162.56 0)
			(effects
				(font
					(size 1.27 1.27)
					(thickness 0.15)
				)
				(justify left bottom)
				(hide yes)
			)
		)
		(property "Description" ""
			(at 81.28 149.86 0)
			(effects
				(font
					(size 1.27 1.27)
				)
				(hide yes)
			)
		)
		(property "Author" "Antmicro"
			(at 90.17 157.48 0)
			(effects
				(font
					(size 1.27 1.27)
					(thickness 0.15)
				)
				(justify left bottom)
				(hide yes)
			)
		)
		(property "License" "Apache-2.0"
			(at 90.17 160.02 0)
			(effects
				(font
					(size 1.27 1.27)
					(thickness 0.15)
				)
				(justify left bottom)
				(hide yes)
			)
		)
		(pin "1"
		)
		(instances
			(project "gmsl-deserializer"
				(path ""
					(reference "#PWR029")
					(unit 1)
				)
			)
		)
	)
	(symbol
		(lib_id "antmicropower:+12V")
		(at 262.89 54.61 0)
		(unit 1)
		(exclude_from_sim no)
		(in_bom yes)
		(on_board yes)
		(dnp no)
		(fields_autoplaced yes)
		(property "Reference" "#PWR042"
			(at 262.89 58.42 0)
			(effects
				(font
					(size 1.27 1.27)
				)
				(hide yes)
			)
		)
		(property "Value" "+12V"
			(at 262.89 49.53 0)
			(effects
				(font
					(size 1.27 1.27)
				)
			)
		)
		(property "Footprint" ""
			(at 262.89 54.61 0)
			(effects
				(font
					(size 1.27 1.27)
				)
				(hide yes)
			)
		)
		(property "Datasheet" ""
			(at 262.89 54.61 0)
			(effects
				(font
					(size 1.27 1.27)
				)
				(hide yes)
			)
		)
		(property "Description" ""
			(at 262.89 54.61 0)
			(effects
				(font
					(size 1.27 1.27)
				)
				(hide yes)
			)
		)
		(pin "1"
		)
		(instances
			(project "gmsl-deserializer"
				(path ""
					(reference "#PWR042")
					(unit 1)
				)
			)
		)
	)
	(symbol
		(lib_id "antmicropower:+12V")
		(at 279.4 121.92 0)
		(unit 1)
		(exclude_from_sim no)
		(in_bom yes)
		(on_board yes)
		(dnp no)
		(fields_autoplaced yes)
		(property "Reference" "#PWR046"
			(at 279.4 125.73 0)
			(effects
				(font
					(size 1.27 1.27)
				)
				(hide yes)
			)
		)
		(property "Value" "+12V"
			(at 279.4 116.84 0)
			(effects
				(font
					(size 1.27 1.27)
				)
			)
		)
		(property "Footprint" ""
			(at 279.4 121.92 0)
			(effects
				(font
					(size 1.27 1.27)
				)
				(hide yes)
			)
		)
		(property "Datasheet" ""
			(at 279.4 121.92 0)
			(effects
				(font
					(size 1.27 1.27)
				)
				(hide yes)
			)
		)
		(property "Description" ""
			(at 279.4 121.92 0)
			(effects
				(font
					(size 1.27 1.27)
				)
				(hide yes)
			)
		)
		(pin "1"
		)
		(instances
			(project "gmsl-deserializer"
				(path ""
					(reference "#PWR046")
					(unit 1)
				)
			)
		)
	)
	(symbol
		(lib_id "antmicropower:GND")
		(at 340.36 73.66 0)
		(unit 1)
		(exclude_from_sim no)
		(in_bom yes)
		(on_board yes)
		(dnp no)
		(property "Reference" "#PWR054"
			(at 349.25 76.2 0)
			(effects
				(font
					(size 1.27 1.27)
					(thickness 0.15)
				)
				(justify left bottom)
				(hide yes)
			)
		)
		(property "Value" "GND"
			(at 340.36 77.47 0)
			(effects
				(font
					(size 1.27 1.27)
					(thickness 0.15)
				)
			)
		)
		(property "Footprint" ""
			(at 349.25 81.28 0)
			(effects
				(font
					(size 1.27 1.27)
					(thickness 0.15)
				)
				(justify left bottom)
				(hide yes)
			)
		)
		(property "Datasheet" ""
			(at 349.25 86.36 0)
			(effects
				(font
					(size 1.27 1.27)
					(thickness 0.15)
				)
				(justify left bottom)
				(hide yes)
			)
		)
		(property "Description" ""
			(at 340.36 73.66 0)
			(effects
				(font
					(size 1.27 1.27)
				)
				(hide yes)
			)
		)
		(property "Author" "Antmicro"
			(at 349.25 81.28 0)
			(effects
				(font
					(size 1.27 1.27)
					(thickness 0.15)
				)
				(justify left bottom)
				(hide yes)
			)
		)
		(property "License" "Apache-2.0"
			(at 349.25 83.82 0)
			(effects
				(font
					(size 1.27 1.27)
					(thickness 0.15)
				)
				(justify left bottom)
				(hide yes)
			)
		)
		(pin "1"
		)
		(instances
			(project "gmsl-deserializer"
				(path ""
					(reference "#PWR054")
					(unit 1)
				)
			)
		)
	)
	(symbol
		(lib_id "antmicroTestPoints:TP_0.75mm_SMD")
		(at 105.41 223.52 90)
		(unit 1)
		(exclude_from_sim no)
		(in_bom yes)
		(on_board yes)
		(dnp no)
		(property "Reference" "TP10"
			(at 104.14 218.44 90)
			(effects
				(font
					(size 1.27 1.27)
					(thickness 0.15)
				)
				(justify right)
			)
		)
		(property "Value" "TP_0.75mm_SMD"
			(at 109.22 212.725 0)
			(effects
				(font
					(size 1.27 1.27)
					(thickness 0.15)
				)
				(justify left bottom)
				(hide yes)
			)
		)
		(property "Footprint" "antmicro-footprints:TP_SMD_0.75mm"
			(at 111.76 212.725 0)
			(effects
				(font
					(size 1.27 1.27)
					(thickness 0.15)
				)
				(justify left bottom)
				(hide yes)
			)
		)
		(property "Datasheet" ""
			(at 118.11 205.74 0)
			(effects
				(font
					(size 1.27 1.27)
					(thickness 0.15)
				)
				(justify left bottom)
				(hide yes)
			)
		)
		(property "Description" "SMT test point"
			(at 105.41 223.52 0)
			(effects
				(font
					(size 1.27 1.27)
				)
				(hide yes)
			)
		)
		(property "MPN" ""
			(at 116.84 212.725 0)
			(effects
				(font
					(size 1.27 1.27)
					(thickness 0.15)
				)
				(justify left bottom)
				(hide yes)
			)
		)
		(property "Manufacturer" ""
			(at 111.76 212.725 0)
			(effects
				(font
					(size 1.27 1.27)
					(thickness 0.15)
				)
				(justify left bottom)
				(hide yes)
			)
		)
		(property "Author" "Antmicro"
			(at 114.3 212.725 0)
			(effects
				(font
					(size 1.27 1.27)
					(thickness 0.15)
				)
				(justify left bottom)
				(hide yes)
			)
		)
		(property "License" "Apache-2.0"
			(at 116.84 212.725 0)
			(effects
				(font
					(size 1.27 1.27)
					(thickness 0.15)
				)
				(justify left bottom)
				(hide yes)
			)
		)
		(pin "1"
		)
		(instances
			(project "gmsl-deserializer"
				(path ""
					(reference "TP10")
					(unit 1)
				)
			)
		)
	)
	(symbol
		(lib_id "antmicroCapacitors0603:C_10u_25V_0603")
		(at 245.11 238.76 90)
		(unit 1)
		(exclude_from_sim no)
		(in_bom yes)
		(on_board yes)
		(dnp no)
		(fields_autoplaced yes)
		(property "Reference" "C16"
			(at 247.65 234.9435 90)
			(effects
				(font
					(size 1.27 1.27)
					(thickness 0.15)
				)
				(justify right)
			)
		)
		(property "Value" "C_10u_25V_0603"
			(at 255.27 218.44 0)
			(effects
				(font
					(size 1.27 1.27)
					(thickness 0.15)
				)
				(justify left bottom)
				(hide yes)
			)
		)
		(property "Footprint" "antmicro-footprints:C_0603_1608Metric"
			(at 257.81 218.44 0)
			(effects
				(font
					(size 1.27 1.27)
					(thickness 0.15)
				)
				(justify left bottom)
				(hide yes)
			)
		)
		(property "Datasheet" "https://product.tdk.com/en/search/capacitor/ceramic/mlcc/info?part_no=C1608X5R1E106M080AC"
			(at 260.35 218.44 0)
			(effects
				(font
					(size 1.27 1.27)
					(thickness 0.15)
				)
				(justify left bottom)
				(hide yes)
			)
		)
		(property "Description" "SMD Multilayer Ceramic Capacitor, 10 µF, 25 V, 0603 [1608 Metric], ± 20%, X5R, C"
			(at 245.11 238.76 0)
			(effects
				(font
					(size 1.27 1.27)
				)
				(hide yes)
			)
		)
		(property "MPN" "C1608X5R1E106M080AC"
			(at 262.89 218.44 0)
			(effects
				(font
					(size 1.27 1.27)
					(thickness 0.15)
				)
				(justify left bottom)
				(hide yes)
			)
		)
		(property "Manufacturer" "TDK"
			(at 265.43 218.44 0)
			(effects
				(font
					(size 1.27 1.27)
					(thickness 0.15)
				)
				(justify left bottom)
				(hide yes)
			)
		)
		(property "License" "Apache-2.0"
			(at 267.97 218.44 0)
			(effects
				(font
					(size 1.27 1.27)
					(thickness 0.15)
				)
				(justify left bottom)
				(hide yes)
			)
		)
		(property "Author" "Antmicro"
			(at 270.51 218.44 0)
			(effects
				(font
					(size 1.27 1.27)
					(thickness 0.15)
				)
				(justify left bottom)
				(hide yes)
			)
		)
		(property "Val" "10u"
			(at 247.65 237.4835 90)
			(effects
				(font
					(size 1.27 1.27)
					(thickness 0.15)
				)
				(justify right)
			)
		)
		(property "Voltage" "25V"
			(at 273.05 218.44 0)
			(effects
				(font
					(size 1.27 1.27)
				)
				(justify left bottom)
				(hide yes)
			)
		)
		(property "Dielectric" ""
			(at 275.59 218.44 0)
			(effects
				(font
					(size 1.27 1.27)
				)
				(justify left bottom)
				(hide yes)
			)
		)
		(pin "1"
		)
		(pin "2"
		)
		(instances
			(project "gmsl-deserializer"
				(path ""
					(reference "C16")
					(unit 1)
				)
			)
		)
	)
	(symbol
		(lib_id "antmicroResistors0402:R_10k_0402")
		(at 327.66 149.86 90)
		(unit 1)
		(exclude_from_sim no)
		(in_bom yes)
		(on_board yes)
		(dnp no)
		(fields_autoplaced yes)
		(property "Reference" "R38"
			(at 329.565 146.0499 90)
			(effects
				(font
					(size 1.27 1.27)
					(thickness 0.15)
				)
				(justify right)
			)
		)
		(property "Value" "R_10k_0402"
			(at 340.36 129.54 0)
			(effects
				(font
					(size 1.27 1.27)
					(thickness 0.15)
				)
				(justify left bottom)
				(hide yes)
			)
		)
		(property "Footprint" "antmicro-footprints:R_0402_1005Metric"
			(at 342.9 129.54 0)
			(effects
				(font
					(size 1.27 1.27)
					(thickness 0.15)
				)
				(justify left bottom)
				(hide yes)
			)
		)
		(property "Datasheet" "https://www.bourns.com/docs/product-datasheets/cr.pdf"
			(at 345.44 129.54 0)
			(effects
				(font
					(size 1.27 1.27)
					(thickness 0.15)
				)
				(justify left bottom)
				(hide yes)
			)
		)
		(property "Description" "SMD Chip Resistor, 10 kohm, ± 1%, 62.5 mW, 0402 [1005 Metric], Thick Film, General Purpose"
			(at 327.66 149.86 0)
			(effects
				(font
					(size 1.27 1.27)
				)
				(hide yes)
			)
		)
		(property "MPN" "CR0402-FX-1002GLF"
			(at 347.98 129.54 0)
			(effects
				(font
					(size 1.27 1.27)
					(thickness 0.15)
				)
				(justify left bottom)
				(hide yes)
			)
		)
		(property "Manufacturer" "Bourns"
			(at 350.52 129.54 0)
			(effects
				(font
					(size 1.27 1.27)
					(thickness 0.15)
				)
				(justify left bottom)
				(hide yes)
			)
		)
		(property "License" "Apache-2.0"
			(at 353.06 129.54 0)
			(effects
				(font
					(size 1.27 1.27)
					(thickness 0.15)
				)
				(justify left bottom)
				(hide yes)
			)
		)
		(property "Author" "Antmicro"
			(at 355.6 129.54 0)
			(effects
				(font
					(size 1.27 1.27)
					(thickness 0.15)
				)
				(justify left bottom)
				(hide yes)
			)
		)
		(property "Val" "10k"
			(at 329.565 148.5899 90)
			(effects
				(font
					(size 1.27 1.27)
					(thickness 0.15)
				)
				(justify right)
			)
		)
		(property "Tolerance" "1%"
			(at 337.82 129.54 0)
			(effects
				(font
					(size 1.27 1.27)
				)
				(justify left bottom)
				(hide yes)
			)
		)
		(pin "1"
		)
		(pin "2"
		)
		(instances
			(project "gmsl-deserializer"
				(path ""
					(reference "R38")
					(unit 1)
				)
			)
		)
	)
	(symbol
		(lib_id "antmicropower:GND")
		(at 88.9 71.12 0)
		(unit 1)
		(exclude_from_sim no)
		(in_bom yes)
		(on_board yes)
		(dnp no)
		(property "Reference" "#PWR030"
			(at 97.79 73.66 0)
			(effects
				(font
					(size 1.27 1.27)
					(thickness 0.15)
				)
				(justify left bottom)
				(hide yes)
			)
		)
		(property "Value" "GND"
			(at 88.9 74.93 0)
			(effects
				(font
					(size 1.27 1.27)
					(thickness 0.15)
				)
			)
		)
		(property "Footprint" ""
			(at 97.79 78.74 0)
			(effects
				(font
					(size 1.27 1.27)
					(thickness 0.15)
				)
				(justify left bottom)
				(hide yes)
			)
		)
		(property "Datasheet" ""
			(at 97.79 83.82 0)
			(effects
				(font
					(size 1.27 1.27)
					(thickness 0.15)
				)
				(justify left bottom)
				(hide yes)
			)
		)
		(property "Description" ""
			(at 88.9 71.12 0)
			(effects
				(font
					(size 1.27 1.27)
				)
				(hide yes)
			)
		)
		(property "Author" "Antmicro"
			(at 97.79 78.74 0)
			(effects
				(font
					(size 1.27 1.27)
					(thickness 0.15)
				)
				(justify left bottom)
				(hide yes)
			)
		)
		(property "License" "Apache-2.0"
			(at 97.79 81.28 0)
			(effects
				(font
					(size 1.27 1.27)
					(thickness 0.15)
				)
				(justify left bottom)
				(hide yes)
			)
		)
		(pin "1"
		)
		(instances
			(project "gmsl-deserializer"
				(path ""
					(reference "#PWR030")
					(unit 1)
				)
			)
		)
	)
	(symbol
		(lib_id "antmicroTransistorsFETsMOSFETsSingle:DMG1012T-7")
		(at 382.27 152.4 0)
		(unit 1)
		(exclude_from_sim no)
		(in_bom yes)
		(on_board yes)
		(dnp no)
		(fields_autoplaced yes)
		(property "Reference" "Q4"
			(at 392.43 148.59 0)
			(effects
				(font
					(size 1.27 1.27)
					(thickness 0.15)
				)
				(justify left)
			)
		)
		(property "Value" "DMG1012T-7"
			(at 392.43 156.21 0)
			(effects
				(font
					(size 1.27 1.27)
					(thickness 0.15)
				)
				(justify left bottom)
				(hide yes)
			)
		)
		(property "Footprint" "antmicro-footprints:SOT-523"
			(at 392.43 158.75 0)
			(effects
				(font
					(size 1.27 1.27)
					(thickness 0.15)
				)
				(justify left bottom)
				(hide yes)
			)
		)
		(property "Datasheet" "https://www.diodes.com/assets/Datasheets/ds31783.pdf"
			(at 392.43 161.29 0)
			(effects
				(font
					(size 1.27 1.27)
					(thickness 0.15)
				)
				(justify left bottom)
				(hide yes)
			)
		)
		(property "Description" "Power MOSFET, N Channel, 20 V, 630 mA, 0.3 ohm, SOT-523, Surface Mount"
			(at 382.27 152.4 0)
			(effects
				(font
					(size 1.27 1.27)
				)
				(hide yes)
			)
		)
		(property "MPN" "DMG1012T-7"
			(at 392.43 151.13 0)
			(effects
				(font
					(size 1.27 1.27)
					(thickness 0.15)
				)
				(justify left)
			)
		)
		(property "Manufacturer" "Diodes Incorporated"
			(at 392.43 153.67 0)
			(effects
				(font
					(size 1.27 1.27)
					(thickness 0.15)
				)
				(justify left bottom)
				(hide yes)
			)
		)
		(property "Author" "Antmicro"
			(at 392.43 163.83 0)
			(effects
				(font
					(size 1.27 1.27)
					(thickness 0.15)
				)
				(justify left bottom)
				(hide yes)
			)
		)
		(property "License" "Apache-2.0"
			(at 392.43 166.37 0)
			(effects
				(font
					(size 1.27 1.27)
					(thickness 0.15)
				)
				(justify left bottom)
				(hide yes)
			)
		)
		(property "Public" ""
			(at 402.59 160.02 0)
			(effects
				(font
					(size 1.27 1.27)
				)
				(justify left bottom)
				(hide yes)
			)
		)
		(pin "2"
		)
		(pin "3"
		)
		(pin "1"
		)
		(instances
			(project "gmsl-deserializer"
				(path ""
					(reference "Q4")
					(unit 1)
				)
			)
		)
	)
	(symbol
		(lib_id "antmicroResistors0402:R_5k1_0402")
		(at 104.14 149.86 0)
		(unit 1)
		(exclude_from_sim no)
		(in_bom yes)
		(on_board yes)
		(dnp no)
		(fields_autoplaced yes)
		(property "Reference" "R22"
			(at 106.68 144.145 0)
			(effects
				(font
					(size 1.27 1.27)
					(thickness 0.15)
				)
			)
		)
		(property "Value" "R_5k1_0402"
			(at 124.46 162.56 0)
			(effects
				(font
					(size 1.27 1.27)
					(thickness 0.15)
				)
				(justify left bottom)
				(hide yes)
			)
		)
		(property "Footprint" "antmicro-footprints:R_0402_1005Metric"
			(at 124.46 165.1 0)
			(effects
				(font
					(size 1.27 1.27)
					(thickness 0.15)
				)
				(justify left bottom)
				(hide yes)
			)
		)
		(property "Datasheet" "https://www.bourns.com/docs/product-datasheets/cr.pdf"
			(at 124.46 167.64 0)
			(effects
				(font
					(size 1.27 1.27)
					(thickness 0.15)
				)
				(justify left bottom)
				(hide yes)
			)
		)
		(property "Description" "SMD Chip Resistor, 5.1 kohm, ± 1%, 63 mW, 0402 [1005 Metric], Thick Film, General Purpose"
			(at 104.14 149.86 0)
			(effects
				(font
					(size 1.27 1.27)
				)
				(hide yes)
			)
		)
		(property "MPN" "CR0402-FX-5101GLF"
			(at 124.46 170.18 0)
			(effects
				(font
					(size 1.27 1.27)
					(thickness 0.15)
				)
				(justify left bottom)
				(hide yes)
			)
		)
		(property "Manufacturer" "Bourns"
			(at 124.46 172.72 0)
			(effects
				(font
					(size 1.27 1.27)
					(thickness 0.15)
				)
				(justify left bottom)
				(hide yes)
			)
		)
		(property "License" "Apache-2.0"
			(at 124.46 175.26 0)
			(effects
				(font
					(size 1.27 1.27)
					(thickness 0.15)
				)
				(justify left bottom)
				(hide yes)
			)
		)
		(property "Author" "Antmicro"
			(at 124.46 177.8 0)
			(effects
				(font
					(size 1.27 1.27)
					(thickness 0.15)
				)
				(justify left bottom)
				(hide yes)
			)
		)
		(property "Val" "5k1"
			(at 106.68 146.685 0)
			(effects
				(font
					(size 1.27 1.27)
					(thickness 0.15)
				)
			)
		)
		(property "Tolerance" "1%"
			(at 124.46 160.02 0)
			(effects
				(font
					(size 1.27 1.27)
				)
				(justify left bottom)
				(hide yes)
			)
		)
		(pin "1"
		)
		(pin "2"
		)
		(instances
			(project "gmsl-deserializer"
				(path ""
					(reference "R22")
					(unit 1)
				)
			)
		)
	)
	(symbol
		(lib_id "antmicroFixedInductors:L_6u8_1A_Coilcraft-1210POC")
		(at 121.92 114.3 0)
		(unit 1)
		(exclude_from_sim no)
		(in_bom yes)
		(on_board yes)
		(dnp no)
		(property "Reference" "L7"
			(at 124.46 109.22 0)
			(effects
				(font
					(size 1.27 1.27)
					(thickness 0.15)
				)
			)
		)
		(property "Value" "L_6u8_1A_Coilcraft-1210POC"
			(at 135.89 116.84 0)
			(effects
				(font
					(size 1.27 1.27)
					(thickness 0.15)
				)
				(justify left bottom)
				(hide yes)
			)
		)
		(property "Footprint" "antmicro-footprints:L_Coilcraft-1210POC"
			(at 135.89 121.92 0)
			(effects
				(font
					(size 1.27 1.27)
					(thickness 0.15)
				)
				(justify left bottom)
				(hide yes)
			)
		)
		(property "Datasheet" "https://www.coilcraft.com/getmedia/5e8de018-68c5-4442-84ce-d5212c44660c/1210poc.pdf"
			(at 135.89 124.46 0)
			(effects
				(font
					(size 1.27 1.27)
					(thickness 0.15)
				)
				(justify left bottom)
				(hide yes)
			)
		)
		(property "Description" "Power Inductor (SMT), 6.8 µH, 9.2 A, Shielded, 12.8 A, XAL7070"
			(at 121.92 114.3 0)
			(effects
				(font
					(size 1.27 1.27)
				)
				(hide yes)
			)
		)
		(property "Val" "6u8/1A"
			(at 124.46 111.76 0)
			(effects
				(font
					(size 1.27 1.27)
					(thickness 0.15)
				)
			)
		)
		(property "Manufacturer" "Coilcraft"
			(at 135.89 127 0)
			(effects
				(font
					(size 1.27 1.27)
					(thickness 0.15)
				)
				(justify left bottom)
				(hide yes)
			)
		)
		(property "MPN" "1210POC-682"
			(at 135.89 129.54 0)
			(effects
				(font
					(size 1.27 1.27)
					(thickness 0.15)
				)
				(justify left bottom)
				(hide yes)
			)
		)
		(property "ISat" "1 A"
			(at 135.89 130.81 0)
			(effects
				(font
					(size 1.27 1.27)
				)
				(justify left)
				(hide yes)
			)
		)
		(property "IMax" "1.36 A"
			(at 135.89 134.62 0)
			(effects
				(font
					(size 1.27 1.27)
					(thickness 0.15)
				)
				(justify left bottom)
				(hide yes)
			)
		)
		(property "Size" "2.67x3.3"
			(at 135.89 137.16 0)
			(effects
				(font
					(size 1.27 1.27)
					(thickness 0.15)
				)
				(justify left bottom)
				(hide yes)
			)
		)
		(property "Author" "Antmicro"
			(at 135.89 139.7 0)
			(effects
				(font
					(size 1.27 1.27)
					(thickness 0.15)
				)
				(justify left bottom)
				(hide yes)
			)
		)
		(property "License" "Apache-2.0"
			(at 135.89 142.24 0)
			(effects
				(font
					(size 1.27 1.27)
					(thickness 0.15)
				)
				(justify left bottom)
				(hide yes)
			)
		)
		(pin "1"
		)
		(pin "2"
		)
		(instances
			(project "gmsl-deserializer"
				(path ""
					(reference "L7")
					(unit 1)
				)
			)
		)
	)
	(symbol
		(lib_id "antmicroCapacitors0402:C_1u_0402")
		(at 334.01 223.52 90)
		(unit 1)
		(exclude_from_sim no)
		(in_bom yes)
		(on_board yes)
		(dnp no)
		(property "Reference" "C59"
			(at 335.28 219.075 90)
			(effects
				(font
					(size 1.27 1.27)
					(thickness 0.15)
				)
				(justify right)
			)
		)
		(property "Value" "C_1u_0402"
			(at 344.17 203.2 0)
			(effects
				(font
					(size 1.27 1.27)
					(thickness 0.15)
				)
				(justify left bottom)
				(hide yes)
			)
		)
		(property "Footprint" "antmicro-footprints:C_0402_1005Metric"
			(at 346.71 203.2 0)
			(effects
				(font
					(size 1.27 1.27)
					(thickness 0.15)
				)
				(justify left bottom)
				(hide yes)
			)
		)
		(property "Datasheet" "https://product.tdk.com/en/search/capacitor/ceramic/mlcc/info?part_no=C1005X6S1A105K050BC"
			(at 349.25 203.2 0)
			(effects
				(font
					(size 1.27 1.27)
					(thickness 0.15)
				)
				(justify left bottom)
				(hide yes)
			)
		)
		(property "Description" "SMD Multilayer Ceramic Capacitor, 1 µF, 10 V, 0402 [1005 Metric], ± 10%, X6S, C"
			(at 334.01 223.52 0)
			(effects
				(font
					(size 1.27 1.27)
				)
				(hide yes)
			)
		)
		(property "MPN" "C1005X6S1A105K050BC"
			(at 351.79 203.2 0)
			(effects
				(font
					(size 1.27 1.27)
					(thickness 0.15)
				)
				(justify left bottom)
				(hide yes)
			)
		)
		(property "Manufacturer" "TDK"
			(at 354.33 203.2 0)
			(effects
				(font
					(size 1.27 1.27)
					(thickness 0.15)
				)
				(justify left bottom)
				(hide yes)
			)
		)
		(property "License" "Apache-2.0"
			(at 356.87 203.2 0)
			(effects
				(font
					(size 1.27 1.27)
					(thickness 0.15)
				)
				(justify left bottom)
				(hide yes)
			)
		)
		(property "Author" "Antmicro"
			(at 359.41 203.2 0)
			(effects
				(font
					(size 1.27 1.27)
					(thickness 0.15)
				)
				(justify left bottom)
				(hide yes)
			)
		)
		(property "Val" "1u"
			(at 335.28 222.885 90)
			(effects
				(font
					(size 1.27 1.27)
					(thickness 0.15)
				)
				(justify right)
			)
		)
		(property "Voltage" ""
			(at 361.95 203.2 0)
			(effects
				(font
					(size 1.27 1.27)
				)
				(justify left bottom)
				(hide yes)
			)
		)
		(property "Dielectric" ""
			(at 364.49 203.2 0)
			(effects
				(font
					(size 1.27 1.27)
				)
				(justify left bottom)
				(hide yes)
			)
		)
		(pin "1"
		)
		(pin "2"
		)
		(instances
			(project "gmsl-deserializer"
				(path ""
					(reference "C59")
					(unit 1)
				)
			)
		)
	)
	(symbol
		(lib_id "antmicroFixedInductors:L_470n_1A_Coilcraft-PFL1609")
		(at 157.48 88.9 0)
		(unit 1)
		(exclude_from_sim no)
		(in_bom yes)
		(on_board yes)
		(dnp no)
		(fields_autoplaced yes)
		(property "Reference" "L14"
			(at 160.02 83.82 0)
			(effects
				(font
					(size 1.27 1.27)
					(thickness 0.15)
				)
			)
		)
		(property "Value" "L_470n_1A_Coilcraft-PFL1609"
			(at 171.45 91.44 0)
			(effects
				(font
					(size 1.27 1.27)
					(thickness 0.15)
				)
				(justify left bottom)
				(hide yes)
			)
		)
		(property "Footprint" "antmicro-footprints:L_Coilcraft-PFL1609"
			(at 171.45 96.52 0)
			(effects
				(font
					(size 1.27 1.27)
					(thickness 0.15)
				)
				(justify left bottom)
				(hide yes)
			)
		)
		(property "Datasheet" "https://www.coilcraft.com/getmedia/2f4cd442-d64d-4413-a518-12fcfd03318d/pfl1609.pdf"
			(at 171.45 99.06 0)
			(effects
				(font
					(size 1.27 1.27)
					(thickness 0.15)
				)
				(justify left bottom)
				(hide yes)
			)
		)
		(property "Description" "Power Inductor (SMT), 6.8 µH, 9.2 A, Shielded, 12.8 A, XAL7070"
			(at 157.48 88.9 0)
			(effects
				(font
					(size 1.27 1.27)
				)
				(hide yes)
			)
		)
		(property "Val" "470n/0.99A"
			(at 160.02 86.36 0)
			(effects
				(font
					(size 1.27 1.27)
					(thickness 0.15)
				)
			)
		)
		(property "Manufacturer" "Coilcraft"
			(at 171.45 101.6 0)
			(effects
				(font
					(size 1.27 1.27)
					(thickness 0.15)
				)
				(justify left bottom)
				(hide yes)
			)
		)
		(property "MPN" "PFL1609-471"
			(at 171.45 104.14 0)
			(effects
				(font
					(size 1.27 1.27)
					(thickness 0.15)
				)
				(justify left bottom)
				(hide yes)
			)
		)
		(property "ISat" "0.99 A"
			(at 171.45 105.41 0)
			(effects
				(font
					(size 1.27 1.27)
				)
				(justify left)
				(hide yes)
			)
		)
		(property "IMax" "1 A"
			(at 171.45 109.22 0)
			(effects
				(font
					(size 1.27 1.27)
					(thickness 0.15)
				)
				(justify left bottom)
				(hide yes)
			)
		)
		(property "Size" "1.07x1.8"
			(at 171.45 111.76 0)
			(effects
				(font
					(size 1.27 1.27)
					(thickness 0.15)
				)
				(justify left bottom)
				(hide yes)
			)
		)
		(property "Author" "Antmicro"
			(at 171.45 114.3 0)
			(effects
				(font
					(size 1.27 1.27)
					(thickness 0.15)
				)
				(justify left bottom)
				(hide yes)
			)
		)
		(property "License" "Apache-2.0"
			(at 171.45 116.84 0)
			(effects
				(font
					(size 1.27 1.27)
					(thickness 0.15)
				)
				(justify left bottom)
				(hide yes)
			)
		)
		(pin "1"
		)
		(pin "2"
		)
		(instances
			(project "gmsl-deserializer"
				(path ""
					(reference "L14")
					(unit 1)
				)
			)
		)
	)
	(symbol
		(lib_id "antmicropower:GND")
		(at 349.25 151.13 0)
		(unit 1)
		(exclude_from_sim no)
		(in_bom yes)
		(on_board yes)
		(dnp no)
		(property "Reference" "#PWR059"
			(at 358.14 153.67 0)
			(effects
				(font
					(size 1.27 1.27)
					(thickness 0.15)
				)
				(justify left bottom)
				(hide yes)
			)
		)
		(property "Value" "GND"
			(at 349.25 154.94 0)
			(effects
				(font
					(size 1.27 1.27)
					(thickness 0.15)
				)
			)
		)
		(property "Footprint" ""
			(at 358.14 158.75 0)
			(effects
				(font
					(size 1.27 1.27)
					(thickness 0.15)
				)
				(justify left bottom)
				(hide yes)
			)
		)
		(property "Datasheet" ""
			(at 358.14 163.83 0)
			(effects
				(font
					(size 1.27 1.27)
					(thickness 0.15)
				)
				(justify left bottom)
				(hide yes)
			)
		)
		(property "Description" ""
			(at 349.25 151.13 0)
			(effects
				(font
					(size 1.27 1.27)
				)
				(hide yes)
			)
		)
		(property "Author" "Antmicro"
			(at 358.14 158.75 0)
			(effects
				(font
					(size 1.27 1.27)
					(thickness 0.15)
				)
				(justify left bottom)
				(hide yes)
			)
		)
		(property "License" "Apache-2.0"
			(at 358.14 161.29 0)
			(effects
				(font
					(size 1.27 1.27)
					(thickness 0.15)
				)
				(justify left bottom)
				(hide yes)
			)
		)
		(pin "1"
		)
		(instances
			(project "gmsl-deserializer"
				(path ""
					(reference "#PWR059")
					(unit 1)
				)
			)
		)
	)
	(symbol
		(lib_id "antmicroCapacitors0402:C_10n_0402")
		(at 88.9 123.19 90)
		(unit 1)
		(exclude_from_sim no)
		(in_bom yes)
		(on_board yes)
		(dnp no)
		(property "Reference" "C12"
			(at 89.535 118.745 90)
			(effects
				(font
					(size 1.27 1.27)
					(thickness 0.15)
				)
				(justify right)
			)
		)
		(property "Value" "C_10n_0402"
			(at 99.06 102.87 0)
			(effects
				(font
					(size 1.27 1.27)
					(thickness 0.15)
				)
				(justify left bottom)
				(hide yes)
			)
		)
		(property "Footprint" "antmicro-footprints:C_0402_1005Metric"
			(at 101.6 102.87 0)
			(effects
				(font
					(size 1.27 1.27)
					(thickness 0.15)
				)
				(justify left bottom)
				(hide yes)
			)
		)
		(property "Datasheet" "https://www.murata.com/products/productdetail?partno=GRM155R71H103KA88%23"
			(at 104.14 102.87 0)
			(effects
				(font
					(size 1.27 1.27)
					(thickness 0.15)
				)
				(justify left bottom)
				(hide yes)
			)
		)
		(property "Description" "SMD Multilayer Ceramic Capacitor, 10000 pF, 50 V, 0402 [1005 Metric], ± 10%, X7R, GRM Series"
			(at 88.9 123.19 0)
			(effects
				(font
					(size 1.27 1.27)
				)
				(hide yes)
			)
		)
		(property "MPN" "GRM155R71H103KA88D"
			(at 106.68 102.87 0)
			(effects
				(font
					(size 1.27 1.27)
					(thickness 0.15)
				)
				(justify left bottom)
				(hide yes)
			)
		)
		(property "Manufacturer" "Murata"
			(at 109.22 102.87 0)
			(effects
				(font
					(size 1.27 1.27)
					(thickness 0.15)
				)
				(justify left bottom)
				(hide yes)
			)
		)
		(property "License" "Apache-2.0"
			(at 111.76 102.87 0)
			(effects
				(font
					(size 1.27 1.27)
					(thickness 0.15)
				)
				(justify left bottom)
				(hide yes)
			)
		)
		(property "Author" "Antmicro"
			(at 114.3 102.87 0)
			(effects
				(font
					(size 1.27 1.27)
					(thickness 0.15)
				)
				(justify left bottom)
				(hide yes)
			)
		)
		(property "Val" "10n"
			(at 89.535 122.555 90)
			(effects
				(font
					(size 1.27 1.27)
					(thickness 0.15)
				)
				(justify right)
			)
		)
		(property "Voltage" "50V"
			(at 116.84 102.87 0)
			(effects
				(font
					(size 1.27 1.27)
				)
				(justify left bottom)
				(hide yes)
			)
		)
		(property "Dielectric" "X7R"
			(at 119.38 102.87 0)
			(effects
				(font
					(size 1.27 1.27)
				)
				(justify left bottom)
				(hide yes)
			)
		)
		(pin "1"
		)
		(pin "2"
		)
		(instances
			(project "gmsl-deserializer"
				(path ""
					(reference "C12")
					(unit 1)
				)
			)
		)
	)
	(symbol
		(lib_id "antmicropower:GND")
		(at 349.25 73.66 0)
		(unit 1)
		(exclude_from_sim no)
		(in_bom yes)
		(on_board yes)
		(dnp no)
		(property "Reference" "#PWR058"
			(at 358.14 76.2 0)
			(effects
				(font
					(size 1.27 1.27)
					(thickness 0.15)
				)
				(justify left bottom)
				(hide yes)
			)
		)
		(property "Value" "GND"
			(at 349.25 77.47 0)
			(effects
				(font
					(size 1.27 1.27)
					(thickness 0.15)
				)
			)
		)
		(property "Footprint" ""
			(at 358.14 81.28 0)
			(effects
				(font
					(size 1.27 1.27)
					(thickness 0.15)
				)
				(justify left bottom)
				(hide yes)
			)
		)
		(property "Datasheet" ""
			(at 358.14 86.36 0)
			(effects
				(font
					(size 1.27 1.27)
					(thickness 0.15)
				)
				(justify left bottom)
				(hide yes)
			)
		)
		(property "Description" ""
			(at 349.25 73.66 0)
			(effects
				(font
					(size 1.27 1.27)
				)
				(hide yes)
			)
		)
		(property "Author" "Antmicro"
			(at 358.14 81.28 0)
			(effects
				(font
					(size 1.27 1.27)
					(thickness 0.15)
				)
				(justify left bottom)
				(hide yes)
			)
		)
		(property "License" "Apache-2.0"
			(at 358.14 83.82 0)
			(effects
				(font
					(size 1.27 1.27)
					(thickness 0.15)
				)
				(justify left bottom)
				(hide yes)
			)
		)
		(pin "1"
		)
		(instances
			(project "gmsl-deserializer"
				(path ""
					(reference "#PWR058")
					(unit 1)
				)
			)
		)
	)
	(symbol
		(lib_id "antmicropower:GND")
		(at 63.5 256.54 0)
		(unit 1)
		(exclude_from_sim no)
		(in_bom yes)
		(on_board yes)
		(dnp no)
		(property "Reference" "#PWR020"
			(at 72.39 259.08 0)
			(effects
				(font
					(size 1.27 1.27)
					(thickness 0.15)
				)
				(justify left bottom)
				(hide yes)
			)
		)
		(property "Value" "GND"
			(at 63.5 260.35 0)
			(effects
				(font
					(size 1.27 1.27)
					(thickness 0.15)
				)
			)
		)
		(property "Footprint" ""
			(at 72.39 264.16 0)
			(effects
				(font
					(size 1.27 1.27)
					(thickness 0.15)
				)
				(justify left bottom)
				(hide yes)
			)
		)
		(property "Datasheet" ""
			(at 72.39 269.24 0)
			(effects
				(font
					(size 1.27 1.27)
					(thickness 0.15)
				)
				(justify left bottom)
				(hide yes)
			)
		)
		(property "Description" ""
			(at 63.5 256.54 0)
			(effects
				(font
					(size 1.27 1.27)
				)
				(hide yes)
			)
		)
		(property "Author" "Antmicro"
			(at 72.39 264.16 0)
			(effects
				(font
					(size 1.27 1.27)
					(thickness 0.15)
				)
				(justify left bottom)
				(hide yes)
			)
		)
		(property "License" "Apache-2.0"
			(at 72.39 266.7 0)
			(effects
				(font
					(size 1.27 1.27)
					(thickness 0.15)
				)
				(justify left bottom)
				(hide yes)
			)
		)
		(pin "1"
		)
		(instances
			(project "gmsl-deserializer"
				(path ""
					(reference "#PWR020")
					(unit 1)
				)
			)
		)
	)
	(symbol
		(lib_id "antmicroCapacitors0603:C_10u_25V_0603")
		(at 262.89 142.24 90)
		(unit 1)
		(exclude_from_sim no)
		(in_bom yes)
		(on_board yes)
		(dnp no)
		(fields_autoplaced yes)
		(property "Reference" "C18"
			(at 265.43 138.4235 90)
			(effects
				(font
					(size 1.27 1.27)
					(thickness 0.15)
				)
				(justify right)
			)
		)
		(property "Value" "C_10u_25V_0603"
			(at 273.05 121.92 0)
			(effects
				(font
					(size 1.27 1.27)
					(thickness 0.15)
				)
				(justify left bottom)
				(hide yes)
			)
		)
		(property "Footprint" "antmicro-footprints:C_0603_1608Metric"
			(at 275.59 121.92 0)
			(effects
				(font
					(size 1.27 1.27)
					(thickness 0.15)
				)
				(justify left bottom)
				(hide yes)
			)
		)
		(property "Datasheet" "https://product.tdk.com/en/search/capacitor/ceramic/mlcc/info?part_no=C1608X5R1E106M080AC"
			(at 278.13 121.92 0)
			(effects
				(font
					(size 1.27 1.27)
					(thickness 0.15)
				)
				(justify left bottom)
				(hide yes)
			)
		)
		(property "Description" "SMD Multilayer Ceramic Capacitor, 10 µF, 25 V, 0603 [1608 Metric], ± 20%, X5R, C"
			(at 262.89 142.24 0)
			(effects
				(font
					(size 1.27 1.27)
				)
				(hide yes)
			)
		)
		(property "MPN" "C1608X5R1E106M080AC"
			(at 280.67 121.92 0)
			(effects
				(font
					(size 1.27 1.27)
					(thickness 0.15)
				)
				(justify left bottom)
				(hide yes)
			)
		)
		(property "Manufacturer" "TDK"
			(at 283.21 121.92 0)
			(effects
				(font
					(size 1.27 1.27)
					(thickness 0.15)
				)
				(justify left bottom)
				(hide yes)
			)
		)
		(property "License" "Apache-2.0"
			(at 285.75 121.92 0)
			(effects
				(font
					(size 1.27 1.27)
					(thickness 0.15)
				)
				(justify left bottom)
				(hide yes)
			)
		)
		(property "Author" "Antmicro"
			(at 288.29 121.92 0)
			(effects
				(font
					(size 1.27 1.27)
					(thickness 0.15)
				)
				(justify left bottom)
				(hide yes)
			)
		)
		(property "Val" "10u"
			(at 265.43 140.9635 90)
			(effects
				(font
					(size 1.27 1.27)
					(thickness 0.15)
				)
				(justify right)
			)
		)
		(property "Voltage" "25V"
			(at 290.83 121.92 0)
			(effects
				(font
					(size 1.27 1.27)
				)
				(justify left bottom)
				(hide yes)
			)
		)
		(property "Dielectric" ""
			(at 293.37 121.92 0)
			(effects
				(font
					(size 1.27 1.27)
				)
				(justify left bottom)
				(hide yes)
			)
		)
		(pin "1"
		)
		(pin "2"
		)
		(instances
			(project "gmsl-deserializer"
				(path ""
					(reference "C18")
					(unit 1)
				)
			)
		)
	)
	(symbol
		(lib_id "antmicropower:GND")
		(at 394.97 226.06 0)
		(unit 1)
		(exclude_from_sim no)
		(in_bom yes)
		(on_board yes)
		(dnp no)
		(property "Reference" "#PWR0110"
			(at 403.86 228.6 0)
			(effects
				(font
					(size 1.27 1.27)
					(thickness 0.15)
				)
				(justify left bottom)
				(hide yes)
			)
		)
		(property "Value" "GND"
			(at 394.97 229.87 0)
			(effects
				(font
					(size 1.27 1.27)
					(thickness 0.15)
				)
			)
		)
		(property "Footprint" ""
			(at 403.86 233.68 0)
			(effects
				(font
					(size 1.27 1.27)
					(thickness 0.15)
				)
				(justify left bottom)
				(hide yes)
			)
		)
		(property "Datasheet" ""
			(at 403.86 238.76 0)
			(effects
				(font
					(size 1.27 1.27)
					(thickness 0.15)
				)
				(justify left bottom)
				(hide yes)
			)
		)
		(property "Description" ""
			(at 394.97 226.06 0)
			(effects
				(font
					(size 1.27 1.27)
				)
				(hide yes)
			)
		)
		(property "Author" "Antmicro"
			(at 403.86 233.68 0)
			(effects
				(font
					(size 1.27 1.27)
					(thickness 0.15)
				)
				(justify left bottom)
				(hide yes)
			)
		)
		(property "License" "Apache-2.0"
			(at 403.86 236.22 0)
			(effects
				(font
					(size 1.27 1.27)
					(thickness 0.15)
				)
				(justify left bottom)
				(hide yes)
			)
		)
		(pin "1"
		)
		(instances
			(project "gmsl-deserializer"
				(path ""
					(reference "#PWR0110")
					(unit 1)
				)
			)
		)
	)
	(symbol
		(lib_id "antmicropower:GND")
		(at 275.59 265.43 0)
		(unit 1)
		(exclude_from_sim no)
		(in_bom yes)
		(on_board yes)
		(dnp no)
		(property "Reference" "#PWR0120"
			(at 284.48 267.97 0)
			(effects
				(font
					(size 1.27 1.27)
					(thickness 0.15)
				)
				(justify left bottom)
				(hide yes)
			)
		)
		(property "Value" "GND"
			(at 275.59 269.24 0)
			(effects
				(font
					(size 1.27 1.27)
					(thickness 0.15)
				)
			)
		)
		(property "Footprint" ""
			(at 284.48 273.05 0)
			(effects
				(font
					(size 1.27 1.27)
					(thickness 0.15)
				)
				(justify left bottom)
				(hide yes)
			)
		)
		(property "Datasheet" ""
			(at 284.48 278.13 0)
			(effects
				(font
					(size 1.27 1.27)
					(thickness 0.15)
				)
				(justify left bottom)
				(hide yes)
			)
		)
		(property "Description" ""
			(at 275.59 265.43 0)
			(effects
				(font
					(size 1.27 1.27)
				)
				(hide yes)
			)
		)
		(property "Author" "Antmicro"
			(at 284.48 273.05 0)
			(effects
				(font
					(size 1.27 1.27)
					(thickness 0.15)
				)
				(justify left bottom)
				(hide yes)
			)
		)
		(property "License" "Apache-2.0"
			(at 284.48 275.59 0)
			(effects
				(font
					(size 1.27 1.27)
					(thickness 0.15)
				)
				(justify left bottom)
				(hide yes)
			)
		)
		(pin "1"
		)
		(instances
			(project "gmsl-deserializer"
				(path ""
					(reference "#PWR0120")
					(unit 1)
				)
			)
		)
	)
	(symbol
		(lib_id "antmicroFixedInductors:L_470n_1A_Coilcraft-PFL1609")
		(at 139.7 62.23 0)
		(unit 1)
		(exclude_from_sim no)
		(in_bom yes)
		(on_board yes)
		(dnp no)
		(fields_autoplaced yes)
		(property "Reference" "L9"
			(at 142.24 57.15 0)
			(effects
				(font
					(size 1.27 1.27)
					(thickness 0.15)
				)
			)
		)
		(property "Value" "L_470n_1A_Coilcraft-PFL1609"
			(at 153.67 64.77 0)
			(effects
				(font
					(size 1.27 1.27)
					(thickness 0.15)
				)
				(justify left bottom)
				(hide yes)
			)
		)
		(property "Footprint" "antmicro-footprints:L_Coilcraft-PFL1609"
			(at 153.67 69.85 0)
			(effects
				(font
					(size 1.27 1.27)
					(thickness 0.15)
				)
				(justify left bottom)
				(hide yes)
			)
		)
		(property "Datasheet" "https://www.coilcraft.com/getmedia/2f4cd442-d64d-4413-a518-12fcfd03318d/pfl1609.pdf"
			(at 153.67 72.39 0)
			(effects
				(font
					(size 1.27 1.27)
					(thickness 0.15)
				)
				(justify left bottom)
				(hide yes)
			)
		)
		(property "Description" "Power Inductor (SMT), 6.8 µH, 9.2 A, Shielded, 12.8 A, XAL7070"
			(at 139.7 62.23 0)
			(effects
				(font
					(size 1.27 1.27)
				)
				(hide yes)
			)
		)
		(property "Val" "470n/0.99A"
			(at 142.24 59.69 0)
			(effects
				(font
					(size 1.27 1.27)
					(thickness 0.15)
				)
			)
		)
		(property "Manufacturer" "Coilcraft"
			(at 153.67 74.93 0)
			(effects
				(font
					(size 1.27 1.27)
					(thickness 0.15)
				)
				(justify left bottom)
				(hide yes)
			)
		)
		(property "MPN" "PFL1609-471"
			(at 153.67 77.47 0)
			(effects
				(font
					(size 1.27 1.27)
					(thickness 0.15)
				)
				(justify left bottom)
				(hide yes)
			)
		)
		(property "ISat" "0.99 A"
			(at 153.67 78.74 0)
			(effects
				(font
					(size 1.27 1.27)
				)
				(justify left)
				(hide yes)
			)
		)
		(property "IMax" "1 A"
			(at 153.67 82.55 0)
			(effects
				(font
					(size 1.27 1.27)
					(thickness 0.15)
				)
				(justify left bottom)
				(hide yes)
			)
		)
		(property "Size" "1.07x1.8"
			(at 153.67 85.09 0)
			(effects
				(font
					(size 1.27 1.27)
					(thickness 0.15)
				)
				(justify left bottom)
				(hide yes)
			)
		)
		(property "Author" "Antmicro"
			(at 153.67 87.63 0)
			(effects
				(font
					(size 1.27 1.27)
					(thickness 0.15)
				)
				(justify left bottom)
				(hide yes)
			)
		)
		(property "License" "Apache-2.0"
			(at 153.67 90.17 0)
			(effects
				(font
					(size 1.27 1.27)
					(thickness 0.15)
				)
				(justify left bottom)
				(hide yes)
			)
		)
		(pin "1"
		)
		(pin "2"
		)
		(instances
			(project "gmsl-deserializer"
				(path ""
					(reference "L9")
					(unit 1)
				)
			)
		)
	)
	(symbol
		(lib_id "antmicroResistors0402:R_5k1_0402")
		(at 121.92 124.46 0)
		(unit 1)
		(exclude_from_sim no)
		(in_bom yes)
		(on_board yes)
		(dnp no)
		(fields_autoplaced yes)
		(property "Reference" "R26"
			(at 124.46 118.745 0)
			(effects
				(font
					(size 1.27 1.27)
					(thickness 0.15)
				)
			)
		)
		(property "Value" "R_5k1_0402"
			(at 142.24 137.16 0)
			(effects
				(font
					(size 1.27 1.27)
					(thickness 0.15)
				)
				(justify left bottom)
				(hide yes)
			)
		)
		(property "Footprint" "antmicro-footprints:R_0402_1005Metric"
			(at 142.24 139.7 0)
			(effects
				(font
					(size 1.27 1.27)
					(thickness 0.15)
				)
				(justify left bottom)
				(hide yes)
			)
		)
		(property "Datasheet" "https://www.bourns.com/docs/product-datasheets/cr.pdf"
			(at 142.24 142.24 0)
			(effects
				(font
					(size 1.27 1.27)
					(thickness 0.15)
				)
				(justify left bottom)
				(hide yes)
			)
		)
		(property "Description" "SMD Chip Resistor, 5.1 kohm, ± 1%, 63 mW, 0402 [1005 Metric], Thick Film, General Purpose"
			(at 121.92 124.46 0)
			(effects
				(font
					(size 1.27 1.27)
				)
				(hide yes)
			)
		)
		(property "MPN" "CR0402-FX-5101GLF"
			(at 142.24 144.78 0)
			(effects
				(font
					(size 1.27 1.27)
					(thickness 0.15)
				)
				(justify left bottom)
				(hide yes)
			)
		)
		(property "Manufacturer" "Bourns"
			(at 142.24 147.32 0)
			(effects
				(font
					(size 1.27 1.27)
					(thickness 0.15)
				)
				(justify left bottom)
				(hide yes)
			)
		)
		(property "License" "Apache-2.0"
			(at 142.24 149.86 0)
			(effects
				(font
					(size 1.27 1.27)
					(thickness 0.15)
				)
				(justify left bottom)
				(hide yes)
			)
		)
		(property "Author" "Antmicro"
			(at 142.24 152.4 0)
			(effects
				(font
					(size 1.27 1.27)
					(thickness 0.15)
				)
				(justify left bottom)
				(hide yes)
			)
		)
		(property "Val" "5k1"
			(at 124.46 121.285 0)
			(effects
				(font
					(size 1.27 1.27)
					(thickness 0.15)
				)
			)
		)
		(property "Tolerance" "1%"
			(at 142.24 134.62 0)
			(effects
				(font
					(size 1.27 1.27)
				)
				(justify left bottom)
				(hide yes)
			)
		)
		(pin "1"
		)
		(pin "2"
		)
		(instances
			(project "gmsl-deserializer"
				(path ""
					(reference "R26")
					(unit 1)
				)
			)
		)
	)
	(symbol
		(lib_id "antmicroResistors0402:R_5k1_0402")
		(at 121.92 72.39 0)
		(unit 1)
		(exclude_from_sim no)
		(in_bom yes)
		(on_board yes)
		(dnp no)
		(fields_autoplaced yes)
		(property "Reference" "R24"
			(at 124.46 66.675 0)
			(effects
				(font
					(size 1.27 1.27)
					(thickness 0.15)
				)
			)
		)
		(property "Value" "R_5k1_0402"
			(at 142.24 85.09 0)
			(effects
				(font
					(size 1.27 1.27)
					(thickness 0.15)
				)
				(justify left bottom)
				(hide yes)
			)
		)
		(property "Footprint" "antmicro-footprints:R_0402_1005Metric"
			(at 142.24 87.63 0)
			(effects
				(font
					(size 1.27 1.27)
					(thickness 0.15)
				)
				(justify left bottom)
				(hide yes)
			)
		)
		(property "Datasheet" "https://www.bourns.com/docs/product-datasheets/cr.pdf"
			(at 142.24 90.17 0)
			(effects
				(font
					(size 1.27 1.27)
					(thickness 0.15)
				)
				(justify left bottom)
				(hide yes)
			)
		)
		(property "Description" "SMD Chip Resistor, 5.1 kohm, ± 1%, 63 mW, 0402 [1005 Metric], Thick Film, General Purpose"
			(at 121.92 72.39 0)
			(effects
				(font
					(size 1.27 1.27)
				)
				(hide yes)
			)
		)
		(property "MPN" "CR0402-FX-5101GLF"
			(at 142.24 92.71 0)
			(effects
				(font
					(size 1.27 1.27)
					(thickness 0.15)
				)
				(justify left bottom)
				(hide yes)
			)
		)
		(property "Manufacturer" "Bourns"
			(at 142.24 95.25 0)
			(effects
				(font
					(size 1.27 1.27)
					(thickness 0.15)
				)
				(justify left bottom)
				(hide yes)
			)
		)
		(property "License" "Apache-2.0"
			(at 142.24 97.79 0)
			(effects
				(font
					(size 1.27 1.27)
					(thickness 0.15)
				)
				(justify left bottom)
				(hide yes)
			)
		)
		(property "Author" "Antmicro"
			(at 142.24 100.33 0)
			(effects
				(font
					(size 1.27 1.27)
					(thickness 0.15)
				)
				(justify left bottom)
				(hide yes)
			)
		)
		(property "Val" "5k1"
			(at 124.46 69.215 0)
			(effects
				(font
					(size 1.27 1.27)
					(thickness 0.15)
				)
			)
		)
		(property "Tolerance" "1%"
			(at 142.24 82.55 0)
			(effects
				(font
					(size 1.27 1.27)
				)
				(justify left bottom)
				(hide yes)
			)
		)
		(pin "1"
		)
		(pin "2"
		)
		(instances
			(project "gmsl-deserializer"
				(path ""
					(reference "R24")
					(unit 1)
				)
			)
		)
	)
	(symbol
		(lib_id "antmicropower:GND")
		(at 81.28 250.19 0)
		(unit 1)
		(exclude_from_sim no)
		(in_bom yes)
		(on_board yes)
		(dnp no)
		(property "Reference" "#PWR021"
			(at 90.17 252.73 0)
			(effects
				(font
					(size 1.27 1.27)
					(thickness 0.15)
				)
				(justify left bottom)
				(hide yes)
			)
		)
		(property "Value" "GND"
			(at 81.28 254 0)
			(effects
				(font
					(size 1.27 1.27)
					(thickness 0.15)
				)
			)
		)
		(property "Footprint" ""
			(at 90.17 257.81 0)
			(effects
				(font
					(size 1.27 1.27)
					(thickness 0.15)
				)
				(justify left bottom)
				(hide yes)
			)
		)
		(property "Datasheet" ""
			(at 90.17 262.89 0)
			(effects
				(font
					(size 1.27 1.27)
					(thickness 0.15)
				)
				(justify left bottom)
				(hide yes)
			)
		)
		(property "Description" ""
			(at 81.28 250.19 0)
			(effects
				(font
					(size 1.27 1.27)
				)
				(hide yes)
			)
		)
		(property "Author" "Antmicro"
			(at 90.17 257.81 0)
			(effects
				(font
					(size 1.27 1.27)
					(thickness 0.15)
				)
				(justify left bottom)
				(hide yes)
			)
		)
		(property "License" "Apache-2.0"
			(at 90.17 260.35 0)
			(effects
				(font
					(size 1.27 1.27)
					(thickness 0.15)
				)
				(justify left bottom)
				(hide yes)
			)
		)
		(pin "1"
		)
		(instances
			(project "gmsl-deserializer"
				(path ""
					(reference "#PWR021")
					(unit 1)
				)
			)
		)
	)
	(symbol
		(lib_id "antmicroCapacitors0402:C_100n_0402")
		(at 81.28 123.19 90)
		(unit 1)
		(exclude_from_sim no)
		(in_bom yes)
		(on_board yes)
		(dnp no)
		(property "Reference" "C8"
			(at 81.915 118.745 90)
			(effects
				(font
					(size 1.27 1.27)
					(thickness 0.15)
				)
				(justify right)
			)
		)
		(property "Value" "C_100n_0402"
			(at 91.44 102.87 0)
			(effects
				(font
					(size 1.27 1.27)
					(thickness 0.15)
				)
				(justify left bottom)
				(hide yes)
			)
		)
		(property "Footprint" "antmicro-footprints:C_0402_1005Metric"
			(at 93.98 102.87 0)
			(effects
				(font
					(size 1.27 1.27)
					(thickness 0.15)
				)
				(justify left bottom)
				(hide yes)
			)
		)
		(property "Datasheet" "https://www.murata.com/products/productdetail?partno=GRM155R61H104KE14%23"
			(at 96.52 102.87 0)
			(effects
				(font
					(size 1.27 1.27)
					(thickness 0.15)
				)
				(justify left bottom)
				(hide yes)
			)
		)
		(property "Description" "SMD Multilayer Ceramic Capacitor, 0.1 µF, 50 V, 0402 [1005 Metric], ± 10%, X5R, GRM Series"
			(at 81.28 123.19 0)
			(effects
				(font
					(size 1.27 1.27)
				)
				(hide yes)
			)
		)
		(property "MPN" "GRM155R61H104KE14D"
			(at 99.06 102.87 0)
			(effects
				(font
					(size 1.27 1.27)
					(thickness 0.15)
				)
				(justify left bottom)
				(hide yes)
			)
		)
		(property "Manufacturer" "Murata"
			(at 101.6 102.87 0)
			(effects
				(font
					(size 1.27 1.27)
					(thickness 0.15)
				)
				(justify left bottom)
				(hide yes)
			)
		)
		(property "License" "Apache-2.0"
			(at 104.14 102.87 0)
			(effects
				(font
					(size 1.27 1.27)
					(thickness 0.15)
				)
				(justify left bottom)
				(hide yes)
			)
		)
		(property "Author" "Antmicro"
			(at 106.68 102.87 0)
			(effects
				(font
					(size 1.27 1.27)
					(thickness 0.15)
				)
				(justify left bottom)
				(hide yes)
			)
		)
		(property "Val" "100n"
			(at 81.915 122.555 90)
			(effects
				(font
					(size 1.27 1.27)
					(thickness 0.15)
				)
				(justify right)
			)
		)
		(property "Voltage" "50V"
			(at 109.22 102.87 0)
			(effects
				(font
					(size 1.27 1.27)
				)
				(justify left bottom)
				(hide yes)
			)
		)
		(property "Dielectric" "X5R"
			(at 111.76 102.87 0)
			(effects
				(font
					(size 1.27 1.27)
				)
				(justify left bottom)
				(hide yes)
			)
		)
		(pin "1"
		)
		(pin "2"
		)
		(instances
			(project "gmsl-deserializer"
				(path ""
					(reference "C8")
					(unit 1)
				)
			)
		)
	)
	(symbol
		(lib_id "antmicroDCDCConverters:AP62301_TSOT")
		(at 288.29 132.08 0)
		(unit 1)
		(exclude_from_sim no)
		(in_bom yes)
		(on_board yes)
		(dnp no)
		(fields_autoplaced yes)
		(property "Reference" "U5"
			(at 298.45 123.825 0)
			(effects
				(font
					(size 1.27 1.27)
					(thickness 0.15)
				)
			)
		)
		(property "Value" "AP62301_TSOT"
			(at 323.85 139.7 0)
			(effects
				(font
					(size 1.27 1.27)
					(thickness 0.15)
				)
				(justify left bottom)
				(hide yes)
			)
		)
		(property "Footprint" "antmicro-footprints:TSOT23-6"
			(at 323.85 142.24 0)
			(effects
				(font
					(size 1.27 1.27)
					(thickness 0.15)
				)
				(justify left bottom)
				(hide yes)
			)
		)
		(property "Datasheet" "https://www.diodes.com/assets/Datasheets/AP62300_AP62301_AP62300T.pdf"
			(at 323.85 144.78 0)
			(effects
				(font
					(size 1.27 1.27)
					(thickness 0.15)
				)
				(justify left bottom)
				(hide yes)
			)
		)
		(property "Description" "DC-DC Switching Synchronous Buck Regulator, Adjustable, 4.2V-18Vin, 0.8V-7V/3A out, TSOT-26-6"
			(at 288.29 132.08 0)
			(effects
				(font
					(size 1.27 1.27)
				)
				(hide yes)
			)
		)
		(property "MPN" "AP62301WU-7"
			(at 298.45 126.365 0)
			(effects
				(font
					(size 1.27 1.27)
					(thickness 0.15)
				)
			)
		)
		(property "Manufacturer" "Diodes Incorporated"
			(at 323.85 147.32 0)
			(effects
				(font
					(size 1.27 1.27)
					(thickness 0.15)
				)
				(justify left bottom)
				(hide yes)
			)
		)
		(property "Author" "Antmicro"
			(at 323.85 149.86 0)
			(effects
				(font
					(size 1.27 1.27)
					(thickness 0.15)
				)
				(justify left bottom)
				(hide yes)
			)
		)
		(property "License" "Apache-2.0"
			(at 323.85 152.4 0)
			(effects
				(font
					(size 1.27 1.27)
					(thickness 0.15)
				)
				(justify left bottom)
				(hide yes)
			)
		)
		(pin "1"
		)
		(pin "2"
		)
		(pin "3"
		)
		(pin "4"
		)
		(pin "5"
		)
		(pin "6"
		)
		(instances
			(project "gmsl-deserializer"
				(path ""
					(reference "U5")
					(unit 1)
				)
			)
		)
	)
	(symbol
		(lib_id "antmicroFixedInductors:L_470n_1A_Coilcraft-PFL1609")
		(at 139.7 88.9 0)
		(unit 1)
		(exclude_from_sim no)
		(in_bom yes)
		(on_board yes)
		(dnp no)
		(fields_autoplaced yes)
		(property "Reference" "L10"
			(at 142.24 83.82 0)
			(effects
				(font
					(size 1.27 1.27)
					(thickness 0.15)
				)
			)
		)
		(property "Value" "L_470n_1A_Coilcraft-PFL1609"
			(at 153.67 91.44 0)
			(effects
				(font
					(size 1.27 1.27)
					(thickness 0.15)
				)
				(justify left bottom)
				(hide yes)
			)
		)
		(property "Footprint" "antmicro-footprints:L_Coilcraft-PFL1609"
			(at 153.67 96.52 0)
			(effects
				(font
					(size 1.27 1.27)
					(thickness 0.15)
				)
				(justify left bottom)
				(hide yes)
			)
		)
		(property "Datasheet" "https://www.coilcraft.com/getmedia/2f4cd442-d64d-4413-a518-12fcfd03318d/pfl1609.pdf"
			(at 153.67 99.06 0)
			(effects
				(font
					(size 1.27 1.27)
					(thickness 0.15)
				)
				(justify left bottom)
				(hide yes)
			)
		)
		(property "Description" "Power Inductor (SMT), 6.8 µH, 9.2 A, Shielded, 12.8 A, XAL7070"
			(at 139.7 88.9 0)
			(effects
				(font
					(size 1.27 1.27)
				)
				(hide yes)
			)
		)
		(property "Val" "470n/0.99A"
			(at 142.24 86.36 0)
			(effects
				(font
					(size 1.27 1.27)
					(thickness 0.15)
				)
			)
		)
		(property "Manufacturer" "Coilcraft"
			(at 153.67 101.6 0)
			(effects
				(font
					(size 1.27 1.27)
					(thickness 0.15)
				)
				(justify left bottom)
				(hide yes)
			)
		)
		(property "MPN" "PFL1609-471"
			(at 153.67 104.14 0)
			(effects
				(font
					(size 1.27 1.27)
					(thickness 0.15)
				)
				(justify left bottom)
				(hide yes)
			)
		)
		(property "ISat" "0.99 A"
			(at 153.67 105.41 0)
			(effects
				(font
					(size 1.27 1.27)
				)
				(justify left)
				(hide yes)
			)
		)
		(property "IMax" "1 A"
			(at 153.67 109.22 0)
			(effects
				(font
					(size 1.27 1.27)
					(thickness 0.15)
				)
				(justify left bottom)
				(hide yes)
			)
		)
		(property "Size" "1.07x1.8"
			(at 153.67 111.76 0)
			(effects
				(font
					(size 1.27 1.27)
					(thickness 0.15)
				)
				(justify left bottom)
				(hide yes)
			)
		)
		(property "Author" "Antmicro"
			(at 153.67 114.3 0)
			(effects
				(font
					(size 1.27 1.27)
					(thickness 0.15)
				)
				(justify left bottom)
				(hide yes)
			)
		)
		(property "License" "Apache-2.0"
			(at 153.67 116.84 0)
			(effects
				(font
					(size 1.27 1.27)
					(thickness 0.15)
				)
				(justify left bottom)
				(hide yes)
			)
		)
		(pin "1"
		)
		(pin "2"
		)
		(instances
			(project "gmsl-deserializer"
				(path ""
					(reference "L10")
					(unit 1)
				)
			)
		)
	)
	(symbol
		(lib_id "antmicroFixedInductors:L_22u_1.12A_Coilcraft-MSS6132T")
		(at 104.14 140.97 0)
		(unit 1)
		(exclude_from_sim no)
		(in_bom yes)
		(on_board yes)
		(dnp no)
		(fields_autoplaced yes)
		(property "Reference" "L4"
			(at 106.68 135.89 0)
			(effects
				(font
					(size 1.27 1.27)
					(thickness 0.15)
				)
			)
		)
		(property "Value" "L_22u_1.12A_Coilcraft-MSS6132T"
			(at 118.11 143.51 0)
			(effects
				(font
					(size 1.27 1.27)
					(thickness 0.15)
				)
				(justify left bottom)
				(hide yes)
			)
		)
		(property "Footprint" "antmicro-footprints:L_Coilcraft-MSS6132T"
			(at 118.11 148.59 0)
			(effects
				(font
					(size 1.27 1.27)
					(thickness 0.15)
				)
				(justify left bottom)
				(hide yes)
			)
		)
		(property "Datasheet" "https://www.coilcraft.com/getmedia/d035c9b3-191d-46aa-ab3f-5c1a849157c1/mss6132t.pdf"
			(at 118.11 151.13 0)
			(effects
				(font
					(size 1.27 1.27)
					(thickness 0.15)
				)
				(justify left bottom)
				(hide yes)
			)
		)
		(property "Description" "Power Inductor (SMT), 22 µH, 1.85 A, Shielded, 2.45 A, WE-MAPI"
			(at 104.14 140.97 0)
			(effects
				(font
					(size 1.27 1.27)
				)
				(hide yes)
			)
		)
		(property "Val" "22u/1.12A"
			(at 106.68 138.43 0)
			(effects
				(font
					(size 1.27 1.27)
					(thickness 0.15)
				)
			)
		)
		(property "Manufacturer" "Coilcraft"
			(at 118.11 153.67 0)
			(effects
				(font
					(size 1.27 1.27)
					(thickness 0.15)
				)
				(justify left bottom)
				(hide yes)
			)
		)
		(property "MPN" "MSS6132T-223"
			(at 118.11 156.21 0)
			(effects
				(font
					(size 1.27 1.27)
					(thickness 0.15)
				)
				(justify left bottom)
				(hide yes)
			)
		)
		(property "ISat" "1.12A"
			(at 118.11 157.48 0)
			(effects
				(font
					(size 1.27 1.27)
				)
				(justify left)
				(hide yes)
			)
		)
		(property "IMax" "1.45A"
			(at 118.11 161.29 0)
			(effects
				(font
					(size 1.27 1.27)
					(thickness 0.15)
				)
				(justify left bottom)
				(hide yes)
			)
		)
		(property "Size" "6.1x6.1"
			(at 118.11 163.83 0)
			(effects
				(font
					(size 1.27 1.27)
					(thickness 0.15)
				)
				(justify left bottom)
				(hide yes)
			)
		)
		(property "Author" "Antmicro"
			(at 118.11 166.37 0)
			(effects
				(font
					(size 1.27 1.27)
					(thickness 0.15)
				)
				(justify left bottom)
				(hide yes)
			)
		)
		(property "License" "Apache-2.0"
			(at 118.11 168.91 0)
			(effects
				(font
					(size 1.27 1.27)
					(thickness 0.15)
				)
				(justify left bottom)
				(hide yes)
			)
		)
		(pin "1"
		)
		(pin "2"
		)
		(instances
			(project "gmsl-deserializer"
				(path ""
					(reference "L4")
					(unit 1)
				)
			)
		)
	)
	(symbol
		(lib_id "antmicropower:GND")
		(at 262.89 67.31 0)
		(unit 1)
		(exclude_from_sim no)
		(in_bom yes)
		(on_board yes)
		(dnp no)
		(property "Reference" "#PWR043"
			(at 271.78 69.85 0)
			(effects
				(font
					(size 1.27 1.27)
					(thickness 0.15)
				)
				(justify left bottom)
				(hide yes)
			)
		)
		(property "Value" "GND"
			(at 262.89 71.12 0)
			(effects
				(font
					(size 1.27 1.27)
					(thickness 0.15)
				)
			)
		)
		(property "Footprint" ""
			(at 271.78 74.93 0)
			(effects
				(font
					(size 1.27 1.27)
					(thickness 0.15)
				)
				(justify left bottom)
				(hide yes)
			)
		)
		(property "Datasheet" ""
			(at 271.78 80.01 0)
			(effects
				(font
					(size 1.27 1.27)
					(thickness 0.15)
				)
				(justify left bottom)
				(hide yes)
			)
		)
		(property "Description" ""
			(at 262.89 67.31 0)
			(effects
				(font
					(size 1.27 1.27)
				)
				(hide yes)
			)
		)
		(property "Author" "Antmicro"
			(at 271.78 74.93 0)
			(effects
				(font
					(size 1.27 1.27)
					(thickness 0.15)
				)
				(justify left bottom)
				(hide yes)
			)
		)
		(property "License" "Apache-2.0"
			(at 271.78 77.47 0)
			(effects
				(font
					(size 1.27 1.27)
					(thickness 0.15)
				)
				(justify left bottom)
				(hide yes)
			)
		)
		(pin "1"
		)
		(instances
			(project "gmsl-deserializer"
				(path ""
					(reference "#PWR043")
					(unit 1)
				)
			)
		)
	)
	(symbol
		(lib_id "antmicroLEDIndicationDiscrete:LED_G_0603_LTST-C190GKT")
		(at 388.62 60.96 270)
		(mirror x)
		(unit 1)
		(exclude_from_sim no)
		(in_bom yes)
		(on_board yes)
		(dnp no)
		(property "Reference" "D20"
			(at 392.43 57.15 90)
			(effects
				(font
					(size 1.27 1.27)
					(thickness 0.15)
				)
				(justify left)
			)
		)
		(property "Value" "LED_G_0603_LTST-C190GKT"
			(at 360.045 55.88 90)
			(effects
				(font
					(size 1.27 1.27)
					(thickness 0.15)
				)
				(justify left)
				(hide yes)
			)
		)
		(property "Footprint" "antmicro-footprints:LED_0603_1608Metric_G"
			(at 378.46 38.1 0)
			(effects
				(font
					(size 1.27 1.27)
					(thickness 0.15)
				)
				(justify left bottom)
				(hide yes)
			)
		)
		(property "Datasheet" "https://media.digikey.com/pdf/Data%20Sheets/Lite-On%20PDFs/LTST-C190GKT.pdf"
			(at 375.92 38.1 0)
			(effects
				(font
					(size 1.27 1.27)
					(thickness 0.15)
				)
				(justify left bottom)
				(hide yes)
			)
		)
		(property "Description" "LED, Green, SMD, 0603, 20 mA, 2.1 V, 569 nm"
			(at 388.62 60.96 0)
			(effects
				(font
					(size 1.27 1.27)
				)
				(hide yes)
			)
		)
		(property "MPN" "LTST-C190GKT"
			(at 392.43 58.42 90)
			(effects
				(font
					(size 1.27 1.27)
					(thickness 0.15)
				)
				(justify left bottom)
			)
		)
		(property "Manufacturer" "Lite-On"
			(at 370.84 38.1 0)
			(effects
				(font
					(size 1.27 1.27)
					(thickness 0.15)
				)
				(justify left bottom)
				(hide yes)
			)
		)
		(property "Author" "Antmicro"
			(at 368.3 38.1 0)
			(effects
				(font
					(size 1.27 1.27)
					(thickness 0.15)
				)
				(justify left bottom)
				(hide yes)
			)
		)
		(property "License" "Apache-2.0"
			(at 365.76 38.1 0)
			(effects
				(font
					(size 1.27 1.27)
					(thickness 0.15)
				)
				(justify left bottom)
				(hide yes)
			)
		)
		(property "VSD_class" "LED"
			(at 363.22 38.1 0)
			(effects
				(font
					(size 1.27 1.27)
				)
				(justify left bottom)
				(hide yes)
			)
		)
		(property "Color" "Green"
			(at 383.54 38.1 0)
			(effects
				(font
					(size 1.27 1.27)
				)
				(justify left bottom)
				(hide yes)
			)
		)
		(pin "1"
		)
		(pin "2"
		)
		(instances
			(project "gmsl-deserializer"
				(path ""
					(reference "D20")
					(unit 1)
				)
			)
		)
	)
	(symbol
		(lib_id "antmicroFixedInductors:L_470n_1A_Coilcraft-PFL1609")
		(at 139.7 140.97 0)
		(unit 1)
		(exclude_from_sim no)
		(in_bom yes)
		(on_board yes)
		(dnp no)
		(fields_autoplaced yes)
		(property "Reference" "L12"
			(at 142.24 135.89 0)
			(effects
				(font
					(size 1.27 1.27)
					(thickness 0.15)
				)
			)
		)
		(property "Value" "L_470n_1A_Coilcraft-PFL1609"
			(at 153.67 143.51 0)
			(effects
				(font
					(size 1.27 1.27)
					(thickness 0.15)
				)
				(justify left bottom)
				(hide yes)
			)
		)
		(property "Footprint" "antmicro-footprints:L_Coilcraft-PFL1609"
			(at 153.67 148.59 0)
			(effects
				(font
					(size 1.27 1.27)
					(thickness 0.15)
				)
				(justify left bottom)
				(hide yes)
			)
		)
		(property "Datasheet" "https://www.coilcraft.com/getmedia/2f4cd442-d64d-4413-a518-12fcfd03318d/pfl1609.pdf"
			(at 153.67 151.13 0)
			(effects
				(font
					(size 1.27 1.27)
					(thickness 0.15)
				)
				(justify left bottom)
				(hide yes)
			)
		)
		(property "Description" "Power Inductor (SMT), 6.8 µH, 9.2 A, Shielded, 12.8 A, XAL7070"
			(at 139.7 140.97 0)
			(effects
				(font
					(size 1.27 1.27)
				)
				(hide yes)
			)
		)
		(property "Val" "470n/0.99A"
			(at 142.24 138.43 0)
			(effects
				(font
					(size 1.27 1.27)
					(thickness 0.15)
				)
			)
		)
		(property "Manufacturer" "Coilcraft"
			(at 153.67 153.67 0)
			(effects
				(font
					(size 1.27 1.27)
					(thickness 0.15)
				)
				(justify left bottom)
				(hide yes)
			)
		)
		(property "MPN" "PFL1609-471"
			(at 153.67 156.21 0)
			(effects
				(font
					(size 1.27 1.27)
					(thickness 0.15)
				)
				(justify left bottom)
				(hide yes)
			)
		)
		(property "ISat" "0.99 A"
			(at 153.67 157.48 0)
			(effects
				(font
					(size 1.27 1.27)
				)
				(justify left)
				(hide yes)
			)
		)
		(property "IMax" "1 A"
			(at 153.67 161.29 0)
			(effects
				(font
					(size 1.27 1.27)
					(thickness 0.15)
				)
				(justify left bottom)
				(hide yes)
			)
		)
		(property "Size" "1.07x1.8"
			(at 153.67 163.83 0)
			(effects
				(font
					(size 1.27 1.27)
					(thickness 0.15)
				)
				(justify left bottom)
				(hide yes)
			)
		)
		(property "Author" "Antmicro"
			(at 153.67 166.37 0)
			(effects
				(font
					(size 1.27 1.27)
					(thickness 0.15)
				)
				(justify left bottom)
				(hide yes)
			)
		)
		(property "License" "Apache-2.0"
			(at 153.67 168.91 0)
			(effects
				(font
					(size 1.27 1.27)
					(thickness 0.15)
				)
				(justify left bottom)
				(hide yes)
			)
		)
		(pin "1"
		)
		(pin "2"
		)
		(instances
			(project "gmsl-deserializer"
				(path ""
					(reference "L12")
					(unit 1)
				)
			)
		)
	)
	(symbol
		(lib_id "antmicroFixedInductors:L_470n_1A_Coilcraft-PFL1609")
		(at 139.7 114.3 0)
		(unit 1)
		(exclude_from_sim no)
		(in_bom yes)
		(on_board yes)
		(dnp no)
		(fields_autoplaced yes)
		(property "Reference" "L11"
			(at 142.24 109.22 0)
			(effects
				(font
					(size 1.27 1.27)
					(thickness 0.15)
				)
			)
		)
		(property "Value" "L_470n_1A_Coilcraft-PFL1609"
			(at 153.67 116.84 0)
			(effects
				(font
					(size 1.27 1.27)
					(thickness 0.15)
				)
				(justify left bottom)
				(hide yes)
			)
		)
		(property "Footprint" "antmicro-footprints:L_Coilcraft-PFL1609"
			(at 153.67 121.92 0)
			(effects
				(font
					(size 1.27 1.27)
					(thickness 0.15)
				)
				(justify left bottom)
				(hide yes)
			)
		)
		(property "Datasheet" "https://www.coilcraft.com/getmedia/2f4cd442-d64d-4413-a518-12fcfd03318d/pfl1609.pdf"
			(at 153.67 124.46 0)
			(effects
				(font
					(size 1.27 1.27)
					(thickness 0.15)
				)
				(justify left bottom)
				(hide yes)
			)
		)
		(property "Description" "Power Inductor (SMT), 6.8 µH, 9.2 A, Shielded, 12.8 A, XAL7070"
			(at 139.7 114.3 0)
			(effects
				(font
					(size 1.27 1.27)
				)
				(hide yes)
			)
		)
		(property "Val" "470n/0.99A"
			(at 142.24 111.76 0)
			(effects
				(font
					(size 1.27 1.27)
					(thickness 0.15)
				)
			)
		)
		(property "Manufacturer" "Coilcraft"
			(at 153.67 127 0)
			(effects
				(font
					(size 1.27 1.27)
					(thickness 0.15)
				)
				(justify left bottom)
				(hide yes)
			)
		)
		(property "MPN" "PFL1609-471"
			(at 153.67 129.54 0)
			(effects
				(font
					(size 1.27 1.27)
					(thickness 0.15)
				)
				(justify left bottom)
				(hide yes)
			)
		)
		(property "ISat" "0.99 A"
			(at 153.67 130.81 0)
			(effects
				(font
					(size 1.27 1.27)
				)
				(justify left)
				(hide yes)
			)
		)
		(property "IMax" "1 A"
			(at 153.67 134.62 0)
			(effects
				(font
					(size 1.27 1.27)
					(thickness 0.15)
				)
				(justify left bottom)
				(hide yes)
			)
		)
		(property "Size" "1.07x1.8"
			(at 153.67 137.16 0)
			(effects
				(font
					(size 1.27 1.27)
					(thickness 0.15)
				)
				(justify left bottom)
				(hide yes)
			)
		)
		(property "Author" "Antmicro"
			(at 153.67 139.7 0)
			(effects
				(font
					(size 1.27 1.27)
					(thickness 0.15)
				)
				(justify left bottom)
				(hide yes)
			)
		)
		(property "License" "Apache-2.0"
			(at 153.67 142.24 0)
			(effects
				(font
					(size 1.27 1.27)
					(thickness 0.15)
				)
				(justify left bottom)
				(hide yes)
			)
		)
		(pin "1"
		)
		(pin "2"
		)
		(instances
			(project "gmsl-deserializer"
				(path ""
					(reference "L11")
					(unit 1)
				)
			)
		)
	)
	(symbol
		(lib_id "antmicroResistors0402:R_4k99_0402")
		(at 327.66 138.43 90)
		(unit 1)
		(exclude_from_sim no)
		(in_bom yes)
		(on_board yes)
		(dnp no)
		(fields_autoplaced yes)
		(property "Reference" "R37"
			(at 330.2 134.6199 90)
			(effects
				(font
					(size 1.27 1.27)
					(thickness 0.15)
				)
				(justify right)
			)
		)
		(property "Value" "R_4k99_0402"
			(at 340.36 118.11 0)
			(effects
				(font
					(size 1.27 1.27)
					(thickness 0.15)
				)
				(justify left bottom)
				(hide yes)
			)
		)
		(property "Footprint" "antmicro-footprints:R_0402_1005Metric"
			(at 342.9 118.11 0)
			(effects
				(font
					(size 1.27 1.27)
					(thickness 0.15)
				)
				(justify left bottom)
				(hide yes)
			)
		)
		(property "Datasheet" "https://www.bourns.com/docs/product-datasheets/cr.pdf"
			(at 345.44 118.11 0)
			(effects
				(font
					(size 1.27 1.27)
					(thickness 0.15)
				)
				(justify left bottom)
				(hide yes)
			)
		)
		(property "Description" "SMD Chip Resistor, 4.99 kohm, ± 1%, 62.5 mW, 0402 [1005 Metric], Thick Film, General Purpose"
			(at 327.66 138.43 0)
			(effects
				(font
					(size 1.27 1.27)
				)
				(hide yes)
			)
		)
		(property "MPN" "CR0402-FX-4991GLF"
			(at 347.98 118.11 0)
			(effects
				(font
					(size 1.27 1.27)
					(thickness 0.15)
				)
				(justify left bottom)
				(hide yes)
			)
		)
		(property "Manufacturer" "Bourns"
			(at 350.52 118.11 0)
			(effects
				(font
					(size 1.27 1.27)
					(thickness 0.15)
				)
				(justify left bottom)
				(hide yes)
			)
		)
		(property "License" "Apache-2.0"
			(at 353.06 118.11 0)
			(effects
				(font
					(size 1.27 1.27)
					(thickness 0.15)
				)
				(justify left bottom)
				(hide yes)
			)
		)
		(property "Author" "Antmicro"
			(at 355.6 118.11 0)
			(effects
				(font
					(size 1.27 1.27)
					(thickness 0.15)
				)
				(justify left bottom)
				(hide yes)
			)
		)
		(property "Val" "4k99"
			(at 330.2 137.1599 90)
			(effects
				(font
					(size 1.27 1.27)
					(thickness 0.15)
				)
				(justify right)
			)
		)
		(property "Tolerance" "1%"
			(at 337.82 118.11 0)
			(effects
				(font
					(size 1.27 1.27)
				)
				(justify left bottom)
				(hide yes)
			)
		)
		(pin "1"
		)
		(pin "2"
		)
		(instances
			(project "gmsl-deserializer"
				(path ""
					(reference "R37")
					(unit 1)
				)
			)
		)
	)
	(symbol
		(lib_id "antmicroTestPoints:TP_0.75mm_SMD")
		(at 67.31 252.73 90)
		(unit 1)
		(exclude_from_sim no)
		(in_bom yes)
		(on_board yes)
		(dnp no)
		(property "Reference" "TP15"
			(at 66.04 247.65 90)
			(effects
				(font
					(size 1.27 1.27)
					(thickness 0.15)
				)
				(justify right)
			)
		)
		(property "Value" "TP_0.75mm_SMD"
			(at 71.12 241.935 0)
			(effects
				(font
					(size 1.27 1.27)
					(thickness 0.15)
				)
				(justify left bottom)
				(hide yes)
			)
		)
		(property "Footprint" "antmicro-footprints:TP_SMD_0.75mm"
			(at 73.66 241.935 0)
			(effects
				(font
					(size 1.27 1.27)
					(thickness 0.15)
				)
				(justify left bottom)
				(hide yes)
			)
		)
		(property "Datasheet" ""
			(at 80.01 234.95 0)
			(effects
				(font
					(size 1.27 1.27)
					(thickness 0.15)
				)
				(justify left bottom)
				(hide yes)
			)
		)
		(property "Description" "SMT test point"
			(at 67.31 252.73 0)
			(effects
				(font
					(size 1.27 1.27)
				)
				(hide yes)
			)
		)
		(property "MPN" ""
			(at 78.74 241.935 0)
			(effects
				(font
					(size 1.27 1.27)
					(thickness 0.15)
				)
				(justify left bottom)
				(hide yes)
			)
		)
		(property "Manufacturer" ""
			(at 73.66 241.935 0)
			(effects
				(font
					(size 1.27 1.27)
					(thickness 0.15)
				)
				(justify left bottom)
				(hide yes)
			)
		)
		(property "Author" "Antmicro"
			(at 76.2 241.935 0)
			(effects
				(font
					(size 1.27 1.27)
					(thickness 0.15)
				)
				(justify left bottom)
				(hide yes)
			)
		)
		(property "License" "Apache-2.0"
			(at 78.74 241.935 0)
			(effects
				(font
					(size 1.27 1.27)
					(thickness 0.15)
				)
				(justify left bottom)
				(hide yes)
			)
		)
		(pin "1"
		)
		(instances
			(project "gmsl-deserializer"
				(path ""
					(reference "TP15")
					(unit 1)
				)
			)
		)
	)
	(symbol
		(lib_id "antmicroResistors0402:R_10k_0402")
		(at 279.4 143.51 90)
		(unit 1)
		(exclude_from_sim no)
		(in_bom yes)
		(on_board yes)
		(dnp no)
		(fields_autoplaced yes)
		(property "Reference" "R65"
			(at 281.305 139.6999 90)
			(effects
				(font
					(size 1.27 1.27)
					(thickness 0.15)
				)
				(justify right)
			)
		)
		(property "Value" "R_10k_0402"
			(at 292.1 123.19 0)
			(effects
				(font
					(size 1.27 1.27)
					(thickness 0.15)
				)
				(justify left bottom)
				(hide yes)
			)
		)
		(property "Footprint" "antmicro-footprints:R_0402_1005Metric"
			(at 294.64 123.19 0)
			(effects
				(font
					(size 1.27 1.27)
					(thickness 0.15)
				)
				(justify left bottom)
				(hide yes)
			)
		)
		(property "Datasheet" "https://www.bourns.com/docs/product-datasheets/cr.pdf"
			(at 297.18 123.19 0)
			(effects
				(font
					(size 1.27 1.27)
					(thickness 0.15)
				)
				(justify left bottom)
				(hide yes)
			)
		)
		(property "Description" "SMD Chip Resistor, 10 kohm, ± 1%, 62.5 mW, 0402 [1005 Metric], Thick Film, General Purpose"
			(at 279.4 143.51 0)
			(effects
				(font
					(size 1.27 1.27)
				)
				(hide yes)
			)
		)
		(property "MPN" "CR0402-FX-1002GLF"
			(at 299.72 123.19 0)
			(effects
				(font
					(size 1.27 1.27)
					(thickness 0.15)
				)
				(justify left bottom)
				(hide yes)
			)
		)
		(property "Manufacturer" "Bourns"
			(at 302.26 123.19 0)
			(effects
				(font
					(size 1.27 1.27)
					(thickness 0.15)
				)
				(justify left bottom)
				(hide yes)
			)
		)
		(property "License" "Apache-2.0"
			(at 304.8 123.19 0)
			(effects
				(font
					(size 1.27 1.27)
					(thickness 0.15)
				)
				(justify left bottom)
				(hide yes)
			)
		)
		(property "Author" "Antmicro"
			(at 307.34 123.19 0)
			(effects
				(font
					(size 1.27 1.27)
					(thickness 0.15)
				)
				(justify left bottom)
				(hide yes)
			)
		)
		(property "Val" "10k"
			(at 281.305 142.2399 90)
			(effects
				(font
					(size 1.27 1.27)
					(thickness 0.15)
				)
				(justify right)
			)
		)
		(property "Tolerance" "1%"
			(at 289.56 123.19 0)
			(effects
				(font
					(size 1.27 1.27)
				)
				(justify left bottom)
				(hide yes)
			)
		)
		(pin "1"
		)
		(pin "2"
		)
		(instances
			(project "gmsl-deserializer"
				(path ""
					(reference "R65")
					(unit 1)
				)
			)
		)
	)
	(symbol
		(lib_id "antmicroCapacitors0603:C_10u_25V_0603")
		(at 262.89 64.77 90)
		(unit 1)
		(exclude_from_sim no)
		(in_bom yes)
		(on_board yes)
		(dnp no)
		(fields_autoplaced yes)
		(property "Reference" "C17"
			(at 265.43 60.9535 90)
			(effects
				(font
					(size 1.27 1.27)
					(thickness 0.15)
				)
				(justify right)
			)
		)
		(property "Value" "C_10u_25V_0603"
			(at 273.05 44.45 0)
			(effects
				(font
					(size 1.27 1.27)
					(thickness 0.15)
				)
				(justify left bottom)
				(hide yes)
			)
		)
		(property "Footprint" "antmicro-footprints:C_0603_1608Metric"
			(at 275.59 44.45 0)
			(effects
				(font
					(size 1.27 1.27)
					(thickness 0.15)
				)
				(justify left bottom)
				(hide yes)
			)
		)
		(property "Datasheet" "https://product.tdk.com/en/search/capacitor/ceramic/mlcc/info?part_no=C1608X5R1E106M080AC"
			(at 278.13 44.45 0)
			(effects
				(font
					(size 1.27 1.27)
					(thickness 0.15)
				)
				(justify left bottom)
				(hide yes)
			)
		)
		(property "Description" "SMD Multilayer Ceramic Capacitor, 10 µF, 25 V, 0603 [1608 Metric], ± 20%, X5R, C"
			(at 262.89 64.77 0)
			(effects
				(font
					(size 1.27 1.27)
				)
				(hide yes)
			)
		)
		(property "MPN" "C1608X5R1E106M080AC"
			(at 280.67 44.45 0)
			(effects
				(font
					(size 1.27 1.27)
					(thickness 0.15)
				)
				(justify left bottom)
				(hide yes)
			)
		)
		(property "Manufacturer" "TDK"
			(at 283.21 44.45 0)
			(effects
				(font
					(size 1.27 1.27)
					(thickness 0.15)
				)
				(justify left bottom)
				(hide yes)
			)
		)
		(property "License" "Apache-2.0"
			(at 285.75 44.45 0)
			(effects
				(font
					(size 1.27 1.27)
					(thickness 0.15)
				)
				(justify left bottom)
				(hide yes)
			)
		)
		(property "Author" "Antmicro"
			(at 288.29 44.45 0)
			(effects
				(font
					(size 1.27 1.27)
					(thickness 0.15)
				)
				(justify left bottom)
				(hide yes)
			)
		)
		(property "Val" "10u"
			(at 265.43 63.4935 90)
			(effects
				(font
					(size 1.27 1.27)
					(thickness 0.15)
				)
				(justify right)
			)
		)
		(property "Voltage" "25V"
			(at 290.83 44.45 0)
			(effects
				(font
					(size 1.27 1.27)
				)
				(justify left bottom)
				(hide yes)
			)
		)
		(property "Dielectric" ""
			(at 293.37 44.45 0)
			(effects
				(font
					(size 1.27 1.27)
				)
				(justify left bottom)
				(hide yes)
			)
		)
		(pin "1"
		)
		(pin "2"
		)
		(instances
			(project "gmsl-deserializer"
				(path ""
					(reference "C17")
					(unit 1)
				)
			)
		)
	)
	(symbol
		(lib_id "antmicroFixedInductors:L_22u_1.12A_Coilcraft-MSS6132T")
		(at 104.14 62.23 0)
		(unit 1)
		(exclude_from_sim no)
		(in_bom yes)
		(on_board yes)
		(dnp no)
		(fields_autoplaced yes)
		(property "Reference" "L1"
			(at 106.68 57.15 0)
			(effects
				(font
					(size 1.27 1.27)
					(thickness 0.15)
				)
			)
		)
		(property "Value" "L_22u_1.12A_Coilcraft-MSS6132T"
			(at 118.11 64.77 0)
			(effects
				(font
					(size 1.27 1.27)
					(thickness 0.15)
				)
				(justify left bottom)
				(hide yes)
			)
		)
		(property "Footprint" "antmicro-footprints:L_Coilcraft-MSS6132T"
			(at 118.11 69.85 0)
			(effects
				(font
					(size 1.27 1.27)
					(thickness 0.15)
				)
				(justify left bottom)
				(hide yes)
			)
		)
		(property "Datasheet" "https://www.coilcraft.com/getmedia/d035c9b3-191d-46aa-ab3f-5c1a849157c1/mss6132t.pdf"
			(at 118.11 72.39 0)
			(effects
				(font
					(size 1.27 1.27)
					(thickness 0.15)
				)
				(justify left bottom)
				(hide yes)
			)
		)
		(property "Description" "Power Inductor (SMT), 22 µH, 1.85 A, Shielded, 2.45 A, WE-MAPI"
			(at 104.14 62.23 0)
			(effects
				(font
					(size 1.27 1.27)
				)
				(hide yes)
			)
		)
		(property "Val" "22u/1.12A"
			(at 106.68 59.69 0)
			(effects
				(font
					(size 1.27 1.27)
					(thickness 0.15)
				)
			)
		)
		(property "Manufacturer" "Coilcraft"
			(at 118.11 74.93 0)
			(effects
				(font
					(size 1.27 1.27)
					(thickness 0.15)
				)
				(justify left bottom)
				(hide yes)
			)
		)
		(property "MPN" "MSS6132T-223"
			(at 118.11 77.47 0)
			(effects
				(font
					(size 1.27 1.27)
					(thickness 0.15)
				)
				(justify left bottom)
				(hide yes)
			)
		)
		(property "ISat" "1.12A"
			(at 118.11 78.74 0)
			(effects
				(font
					(size 1.27 1.27)
				)
				(justify left)
				(hide yes)
			)
		)
		(property "IMax" "1.45A"
			(at 118.11 82.55 0)
			(effects
				(font
					(size 1.27 1.27)
					(thickness 0.15)
				)
				(justify left bottom)
				(hide yes)
			)
		)
		(property "Size" "6.1x6.1"
			(at 118.11 85.09 0)
			(effects
				(font
					(size 1.27 1.27)
					(thickness 0.15)
				)
				(justify left bottom)
				(hide yes)
			)
		)
		(property "Author" "Antmicro"
			(at 118.11 87.63 0)
			(effects
				(font
					(size 1.27 1.27)
					(thickness 0.15)
				)
				(justify left bottom)
				(hide yes)
			)
		)
		(property "License" "Apache-2.0"
			(at 118.11 90.17 0)
			(effects
				(font
					(size 1.27 1.27)
					(thickness 0.15)
				)
				(justify left bottom)
				(hide yes)
			)
		)
		(pin "1"
		)
		(pin "2"
		)
		(instances
			(project "gmsl-deserializer"
				(path ""
					(reference "L1")
					(unit 1)
				)
			)
		)
	)
	(symbol
		(lib_id "antmicroCapacitors0402:C_22u_0402")
		(at 340.36 72.39 90)
		(unit 1)
		(exclude_from_sim no)
		(in_bom yes)
		(on_board yes)
		(dnp no)
		(fields_autoplaced yes)
		(property "Reference" "C21"
			(at 343.535 68.5735 90)
			(effects
				(font
					(size 1.27 1.27)
					(thickness 0.15)
				)
				(justify right)
			)
		)
		(property "Value" "C_22u_0402"
			(at 350.52 52.07 0)
			(effects
				(font
					(size 1.27 1.27)
					(thickness 0.15)
				)
				(justify left bottom)
				(hide yes)
			)
		)
		(property "Footprint" "antmicro-footprints:C_0402_1005Metric"
			(at 353.06 52.07 0)
			(effects
				(font
					(size 1.27 1.27)
					(thickness 0.15)
				)
				(justify left bottom)
				(hide yes)
			)
		)
		(property "Datasheet" "https://www.murata.com/products/productdetail?partno=GRM158R60J226ME01%23"
			(at 355.6 52.07 0)
			(effects
				(font
					(size 1.27 1.27)
					(thickness 0.15)
				)
				(justify left bottom)
				(hide yes)
			)
		)
		(property "Description" "SMD Multilayer Ceramic Capacitor, 22 uF, 4 V, 0402 [1005 Metric], X6S"
			(at 340.36 72.39 0)
			(effects
				(font
					(size 1.27 1.27)
				)
				(hide yes)
			)
		)
		(property "MPN" "GRM158R60J226ME01D"
			(at 358.14 52.07 0)
			(effects
				(font
					(size 1.27 1.27)
					(thickness 0.15)
				)
				(justify left bottom)
				(hide yes)
			)
		)
		(property "Manufacturer" "Murata"
			(at 360.68 52.07 0)
			(effects
				(font
					(size 1.27 1.27)
					(thickness 0.15)
				)
				(justify left bottom)
				(hide yes)
			)
		)
		(property "License" "Apache-2.0"
			(at 363.22 52.07 0)
			(effects
				(font
					(size 1.27 1.27)
					(thickness 0.15)
				)
				(justify left bottom)
				(hide yes)
			)
		)
		(property "Author" "Antmicro"
			(at 365.76 52.07 0)
			(effects
				(font
					(size 1.27 1.27)
					(thickness 0.15)
				)
				(justify left bottom)
				(hide yes)
			)
		)
		(property "Val" "22u"
			(at 343.535 71.1135 90)
			(effects
				(font
					(size 1.27 1.27)
					(thickness 0.15)
				)
				(justify right)
			)
		)
		(property "Voltage" ""
			(at 368.3 52.07 0)
			(effects
				(font
					(size 1.27 1.27)
				)
				(justify left bottom)
				(hide yes)
			)
		)
		(property "Dielectric" ""
			(at 370.84 52.07 0)
			(effects
				(font
					(size 1.27 1.27)
				)
				(justify left bottom)
				(hide yes)
			)
		)
		(pin "1"
		)
		(pin "2"
		)
		(instances
			(project "gmsl-deserializer"
				(path ""
					(reference "C21")
					(unit 1)
				)
			)
		)
	)
	(symbol
		(lib_id "antmicropower:PWR_FLAG")
		(at 363.22 54.61 0)
		(unit 1)
		(exclude_from_sim no)
		(in_bom yes)
		(on_board yes)
		(dnp no)
		(property "Reference" "#FLG0108"
			(at 363.22 52.705 0)
			(effects
				(font
					(size 1.27 1.27)
				)
				(hide yes)
			)
		)
		(property "Value" "PWR_FLAG"
			(at 363.22 50.8 0)
			(effects
				(font
					(size 1.27 1.27)
				)
			)
		)
		(property "Footprint" ""
			(at 363.22 54.61 0)
			(effects
				(font
					(size 1.27 1.27)
				)
				(hide yes)
			)
		)
		(property "Datasheet" ""
			(at 363.22 54.61 0)
			(effects
				(font
					(size 1.27 1.27)
				)
				(hide yes)
			)
		)
		(property "Description" ""
			(at 363.22 54.61 0)
			(effects
				(font
					(size 1.27 1.27)
				)
				(hide yes)
			)
		)
		(pin "1"
		)
		(instances
			(project "gmsl-deserializer"
				(path ""
					(reference "#FLG0108")
					(unit 1)
				)
			)
		)
	)
	(symbol
		(lib_id "antmicroLEDIndicationDiscrete:LED_G_0603_LTST-C190GKT")
		(at 275.59 256.54 270)
		(mirror x)
		(unit 1)
		(exclude_from_sim no)
		(in_bom yes)
		(on_board yes)
		(dnp no)
		(property "Reference" "D18"
			(at 279.4 252.73 90)
			(effects
				(font
					(size 1.27 1.27)
					(thickness 0.15)
				)
				(justify left)
			)
		)
		(property "Value" "LED_G_0603_LTST-C190GKT"
			(at 247.015 251.46 90)
			(effects
				(font
					(size 1.27 1.27)
					(thickness 0.15)
				)
				(justify left)
				(hide yes)
			)
		)
		(property "Footprint" "antmicro-footprints:LED_0603_1608Metric_G"
			(at 265.43 233.68 0)
			(effects
				(font
					(size 1.27 1.27)
					(thickness 0.15)
				)
				(justify left bottom)
				(hide yes)
			)
		)
		(property "Datasheet" "https://media.digikey.com/pdf/Data%20Sheets/Lite-On%20PDFs/LTST-C190GKT.pdf"
			(at 262.89 233.68 0)
			(effects
				(font
					(size 1.27 1.27)
					(thickness 0.15)
				)
				(justify left bottom)
				(hide yes)
			)
		)
		(property "Description" "LED, Green, SMD, 0603, 20 mA, 2.1 V, 569 nm"
			(at 275.59 256.54 0)
			(effects
				(font
					(size 1.27 1.27)
				)
				(hide yes)
			)
		)
		(property "MPN" "LTST-C190GKT"
			(at 279.4 254 90)
			(effects
				(font
					(size 1.27 1.27)
					(thickness 0.15)
				)
				(justify left bottom)
			)
		)
		(property "Manufacturer" "Lite-On"
			(at 257.81 233.68 0)
			(effects
				(font
					(size 1.27 1.27)
					(thickness 0.15)
				)
				(justify left bottom)
				(hide yes)
			)
		)
		(property "Author" "Antmicro"
			(at 255.27 233.68 0)
			(effects
				(font
					(size 1.27 1.27)
					(thickness 0.15)
				)
				(justify left bottom)
				(hide yes)
			)
		)
		(property "License" "Apache-2.0"
			(at 252.73 233.68 0)
			(effects
				(font
					(size 1.27 1.27)
					(thickness 0.15)
				)
				(justify left bottom)
				(hide yes)
			)
		)
		(property "VSD_class" "LED"
			(at 250.19 233.68 0)
			(effects
				(font
					(size 1.27 1.27)
				)
				(justify left bottom)
				(hide yes)
			)
		)
		(property "Color" "Green"
			(at 270.51 233.68 0)
			(effects
				(font
					(size 1.27 1.27)
				)
				(justify left bottom)
				(hide yes)
			)
		)
		(pin "1"
		)
		(pin "2"
		)
		(instances
			(project "gmsl-deserializer"
				(path ""
					(reference "D18")
					(unit 1)
				)
			)
		)
	)
	(symbol
		(lib_id "antmicroFixedInductors:L_1u_2.6A_0806")
		(at 321.31 55.88 0)
		(unit 1)
		(exclude_from_sim no)
		(in_bom yes)
		(on_board yes)
		(dnp no)
		(fields_autoplaced yes)
		(property "Reference" "L18"
			(at 323.85 50.165 0)
			(effects
				(font
					(size 1.27 1.27)
					(thickness 0.15)
				)
			)
		)
		(property "Value" "L_1u_2.6A_0806"
			(at 335.28 58.42 0)
			(effects
				(font
					(size 1.27 1.27)
					(thickness 0.15)
				)
				(justify left bottom)
				(hide yes)
			)
		)
		(property "Footprint" "antmicro-footprints:L_0806_2016Metric"
			(at 335.28 63.5 0)
			(effects
				(font
					(size 1.27 1.27)
					(thickness 0.15)
				)
				(justify left bottom)
				(hide yes)
			)
		)
		(property "Datasheet" "https://www.bourns.com/docs/Product-Datasheets/SRP2010.pdf"
			(at 335.28 66.04 0)
			(effects
				(font
					(size 1.27 1.27)
					(thickness 0.15)
				)
				(justify left bottom)
				(hide yes)
			)
		)
		(property "Description" "Wirewound Inductor, 1 µH, 0.072 ohm, 2.6 A, SRP2010"
			(at 321.31 55.88 0)
			(effects
				(font
					(size 1.27 1.27)
				)
				(hide yes)
			)
		)
		(property "Val" "1u/2.6A"
			(at 323.85 52.705 0)
			(effects
				(font
					(size 1.27 1.27)
					(thickness 0.15)
				)
			)
		)
		(property "Manufacturer" "Bourns"
			(at 335.28 68.58 0)
			(effects
				(font
					(size 1.27 1.27)
					(thickness 0.15)
				)
				(justify left bottom)
				(hide yes)
			)
		)
		(property "MPN" "SRP2010-1R0M"
			(at 335.28 71.12 0)
			(effects
				(font
					(size 1.27 1.27)
					(thickness 0.15)
				)
				(justify left bottom)
				(hide yes)
			)
		)
		(property "ISat" "2.9 A"
			(at 335.28 72.39 0)
			(effects
				(font
					(size 1.27 1.27)
				)
				(justify left)
				(hide yes)
			)
		)
		(property "IMax" "2.6 A"
			(at 335.28 76.2 0)
			(effects
				(font
					(size 1.27 1.27)
					(thickness 0.15)
				)
				(justify left bottom)
				(hide yes)
			)
		)
		(property "Size" "2.0x1.6"
			(at 335.28 78.74 0)
			(effects
				(font
					(size 1.27 1.27)
					(thickness 0.15)
				)
				(justify left bottom)
				(hide yes)
			)
		)
		(property "Author" "Antmicro"
			(at 335.28 81.28 0)
			(effects
				(font
					(size 1.27 1.27)
					(thickness 0.15)
				)
				(justify left bottom)
				(hide yes)
			)
		)
		(property "License" "Apache-2.0"
			(at 335.28 83.82 0)
			(effects
				(font
					(size 1.27 1.27)
					(thickness 0.15)
				)
				(justify left bottom)
				(hide yes)
			)
		)
		(pin "1"
		)
		(pin "2"
		)
		(instances
			(project "gmsl-deserializer"
				(path ""
					(reference "L18")
					(unit 1)
				)
			)
		)
	)
	(symbol
		(lib_id "antmicroPMICPowerDistributionSwitchesLoadDrivers:AP22615A_TSOT26")
		(at 359.41 217.17 0)
		(unit 1)
		(exclude_from_sim no)
		(in_bom yes)
		(on_board yes)
		(dnp no)
		(fields_autoplaced yes)
		(property "Reference" "U6"
			(at 367.03 208.915 0)
			(effects
				(font
					(size 1.27 1.27)
					(thickness 0.15)
				)
			)
		)
		(property "Value" "AP22615A_TSOT26"
			(at 367.03 211.455 0)
			(effects
				(font
					(size 1.27 1.27)
					(thickness 0.15)
				)
			)
		)
		(property "Footprint" "antmicro-footprints:TSOT23-6"
			(at 389.89 224.79 0)
			(effects
				(font
					(size 1.27 1.27)
					(thickness 0.15)
				)
				(justify left bottom)
				(hide yes)
			)
		)
		(property "Datasheet" "https://www.mouser.com/datasheet/2/115/DIOD_S_A0008958405_1-2543193.pdf"
			(at 389.89 227.33 0)
			(effects
				(font
					(size 1.27 1.27)
					(thickness 0.15)
				)
				(justify left bottom)
				(hide yes)
			)
		)
		(property "Description" "Power Load Distribution Switch, High Side, Active High, 1 Output, 5.5 V, 3.6 A, 0.04 ohm, TSOT-26-6"
			(at 359.41 217.17 0)
			(effects
				(font
					(size 1.27 1.27)
				)
				(hide yes)
			)
		)
		(property "MPN" "AP22615AWU-7"
			(at 389.89 229.87 0)
			(effects
				(font
					(size 1.27 1.27)
					(thickness 0.15)
				)
				(justify left bottom)
				(hide yes)
			)
		)
		(property "Manufacturer" "Diodes Incorporated"
			(at 389.89 232.41 0)
			(effects
				(font
					(size 1.27 1.27)
					(thickness 0.15)
				)
				(justify left bottom)
				(hide yes)
			)
		)
		(property "Author" "Antmicro"
			(at 389.89 234.95 0)
			(effects
				(font
					(size 1.27 1.27)
					(thickness 0.15)
				)
				(justify left bottom)
				(hide yes)
			)
		)
		(property "License" "Apache-2.0"
			(at 389.89 237.49 0)
			(effects
				(font
					(size 1.27 1.27)
					(thickness 0.15)
				)
				(justify left bottom)
				(hide yes)
			)
		)
		(pin "1"
		)
		(pin "2"
		)
		(pin "3"
		)
		(pin "4"
		)
		(pin "5"
		)
		(pin "6"
		)
		(instances
			(project "gmsl-deserializer"
				(path ""
					(reference "U6")
					(unit 1)
				)
			)
		)
	)
	(symbol
		(lib_id "antmicroFixedInductors:L_470n_1A_Coilcraft-PFL1609")
		(at 157.48 140.97 0)
		(unit 1)
		(exclude_from_sim no)
		(in_bom yes)
		(on_board yes)
		(dnp no)
		(fields_autoplaced yes)
		(property "Reference" "L16"
			(at 160.02 135.89 0)
			(effects
				(font
					(size 1.27 1.27)
					(thickness 0.15)
				)
			)
		)
		(property "Value" "L_470n_1A_Coilcraft-PFL1609"
			(at 171.45 143.51 0)
			(effects
				(font
					(size 1.27 1.27)
					(thickness 0.15)
				)
				(justify left bottom)
				(hide yes)
			)
		)
		(property "Footprint" "antmicro-footprints:L_Coilcraft-PFL1609"
			(at 171.45 148.59 0)
			(effects
				(font
					(size 1.27 1.27)
					(thickness 0.15)
				)
				(justify left bottom)
				(hide yes)
			)
		)
		(property "Datasheet" "https://www.coilcraft.com/getmedia/2f4cd442-d64d-4413-a518-12fcfd03318d/pfl1609.pdf"
			(at 171.45 151.13 0)
			(effects
				(font
					(size 1.27 1.27)
					(thickness 0.15)
				)
				(justify left bottom)
				(hide yes)
			)
		)
		(property "Description" "Power Inductor (SMT), 6.8 µH, 9.2 A, Shielded, 12.8 A, XAL7070"
			(at 157.48 140.97 0)
			(effects
				(font
					(size 1.27 1.27)
				)
				(hide yes)
			)
		)
		(property "Val" "470n/0.99A"
			(at 160.02 138.43 0)
			(effects
				(font
					(size 1.27 1.27)
					(thickness 0.15)
				)
			)
		)
		(property "Manufacturer" "Coilcraft"
			(at 171.45 153.67 0)
			(effects
				(font
					(size 1.27 1.27)
					(thickness 0.15)
				)
				(justify left bottom)
				(hide yes)
			)
		)
		(property "MPN" "PFL1609-471"
			(at 171.45 156.21 0)
			(effects
				(font
					(size 1.27 1.27)
					(thickness 0.15)
				)
				(justify left bottom)
				(hide yes)
			)
		)
		(property "ISat" "0.99 A"
			(at 171.45 157.48 0)
			(effects
				(font
					(size 1.27 1.27)
				)
				(justify left)
				(hide yes)
			)
		)
		(property "IMax" "1 A"
			(at 171.45 161.29 0)
			(effects
				(font
					(size 1.27 1.27)
					(thickness 0.15)
				)
				(justify left bottom)
				(hide yes)
			)
		)
		(property "Size" "1.07x1.8"
			(at 171.45 163.83 0)
			(effects
				(font
					(size 1.27 1.27)
					(thickness 0.15)
				)
				(justify left bottom)
				(hide yes)
			)
		)
		(property "Author" "Antmicro"
			(at 171.45 166.37 0)
			(effects
				(font
					(size 1.27 1.27)
					(thickness 0.15)
				)
				(justify left bottom)
				(hide yes)
			)
		)
		(property "License" "Apache-2.0"
			(at 171.45 168.91 0)
			(effects
				(font
					(size 1.27 1.27)
					(thickness 0.15)
				)
				(justify left bottom)
				(hide yes)
			)
		)
		(pin "1"
		)
		(pin "2"
		)
		(instances
			(project "gmsl-deserializer"
				(path ""
					(reference "L16")
					(unit 1)
				)
			)
		)
	)
	(symbol
		(lib_id "antmicroTransistorsFETsMOSFETsSingle:SQS401EN-T1_BE3")
		(at 95.25 231.14 90)
		(unit 1)
		(exclude_from_sim no)
		(in_bom yes)
		(on_board yes)
		(dnp no)
		(property "Reference" "Q2"
			(at 102.235 222.25 90)
			(effects
				(font
					(size 1.27 1.27)
					(thickness 0.15)
				)
			)
		)
		(property "Value" "SQS401EN-T1_BE3"
			(at 85.09 246.38 0)
			(effects
				(font
					(size 1.27 1.27)
					(thickness 0.15)
				)
				(justify left bottom)
				(hide yes)
			)
		)
		(property "Footprint" "antmicro-footprints:Vishay_PowerPAK_1212-8_Single"
			(at 82.55 246.38 0)
			(effects
				(font
					(size 1.27 1.27)
					(thickness 0.15)
				)
				(justify left bottom)
				(hide yes)
			)
		)
		(property "Datasheet" "https://www.vishay.com/docs/65529/sqs401en.pdf"
			(at 80.01 246.38 0)
			(effects
				(font
					(size 1.27 1.27)
					(thickness 0.15)
				)
				(justify left bottom)
				(hide yes)
			)
		)
		(property "Description" "MOSFET, P Channel, 40 V, 16A, 0.047 ohm, PowerPAK 1212-8, Surface Mount"
			(at 95.25 231.14 0)
			(effects
				(font
					(size 1.27 1.27)
				)
				(hide yes)
			)
		)
		(property "MPN" "SQS401EN-T1_BE3"
			(at 110.49 227.33 90)
			(effects
				(font
					(size 1.27 1.27)
					(thickness 0.15)
				)
			)
		)
		(property "Manufacturer" "Vishay"
			(at 77.47 246.38 0)
			(effects
				(font
					(size 1.27 1.27)
					(thickness 0.15)
				)
				(justify left bottom)
				(hide yes)
			)
		)
		(property "Author" "Antmicro"
			(at 74.93 246.38 0)
			(effects
				(font
					(size 1.27 1.27)
					(thickness 0.15)
				)
				(justify left bottom)
				(hide yes)
			)
		)
		(property "License" "Apache-2.0"
			(at 72.39 246.38 0)
			(effects
				(font
					(size 1.27 1.27)
					(thickness 0.15)
				)
				(justify left bottom)
				(hide yes)
			)
		)
		(pin "1"
		)
		(pin "2"
		)
		(pin "3"
		)
		(pin "4"
		)
		(pin "5"
		)
		(instances
			(project "gmsl-deserializer"
				(path ""
					(reference "Q2")
					(unit 1)
				)
			)
		)
	)
	(symbol
		(lib_id "antmicropower:+12V")
		(at 262.89 130.81 0)
		(unit 1)
		(exclude_from_sim no)
		(in_bom yes)
		(on_board yes)
		(dnp no)
		(fields_autoplaced yes)
		(property "Reference" "#PWR044"
			(at 262.89 134.62 0)
			(effects
				(font
					(size 1.27 1.27)
				)
				(hide yes)
			)
		)
		(property "Value" "+12V"
			(at 262.89 125.73 0)
			(effects
				(font
					(size 1.27 1.27)
				)
			)
		)
		(property "Footprint" ""
			(at 262.89 130.81 0)
			(effects
				(font
					(size 1.27 1.27)
				)
				(hide yes)
			)
		)
		(property "Datasheet" ""
			(at 262.89 130.81 0)
			(effects
				(font
					(size 1.27 1.27)
				)
				(hide yes)
			)
		)
		(property "Description" ""
			(at 262.89 130.81 0)
			(effects
				(font
					(size 1.27 1.27)
				)
				(hide yes)
			)
		)
		(pin "1"
		)
		(instances
			(project "gmsl-deserializer"
				(path ""
					(reference "#PWR044")
					(unit 1)
				)
			)
		)
	)
	(symbol
		(lib_id "antmicropower:GND")
		(at 88.9 123.19 0)
		(unit 1)
		(exclude_from_sim no)
		(in_bom yes)
		(on_board yes)
		(dnp no)
		(property "Reference" "#PWR032"
			(at 97.79 125.73 0)
			(effects
				(font
					(size 1.27 1.27)
					(thickness 0.15)
				)
				(justify left bottom)
				(hide yes)
			)
		)
		(property "Value" "GND"
			(at 88.9 127 0)
			(effects
				(font
					(size 1.27 1.27)
					(thickness 0.15)
				)
			)
		)
		(property "Footprint" ""
			(at 97.79 130.81 0)
			(effects
				(font
					(size 1.27 1.27)
					(thickness 0.15)
				)
				(justify left bottom)
				(hide yes)
			)
		)
		(property "Datasheet" ""
			(at 97.79 135.89 0)
			(effects
				(font
					(size 1.27 1.27)
					(thickness 0.15)
				)
				(justify left bottom)
				(hide yes)
			)
		)
		(property "Description" ""
			(at 88.9 123.19 0)
			(effects
				(font
					(size 1.27 1.27)
				)
				(hide yes)
			)
		)
		(property "Author" "Antmicro"
			(at 97.79 130.81 0)
			(effects
				(font
					(size 1.27 1.27)
					(thickness 0.15)
				)
				(justify left bottom)
				(hide yes)
			)
		)
		(property "License" "Apache-2.0"
			(at 97.79 133.35 0)
			(effects
				(font
					(size 1.27 1.27)
					(thickness 0.15)
				)
				(justify left bottom)
				(hide yes)
			)
		)
		(pin "1"
		)
		(instances
			(project "gmsl-deserializer"
				(path ""
					(reference "#PWR032")
					(unit 1)
				)
			)
		)
	)
	(symbol
		(lib_id "antmicropower:GND")
		(at 327.66 151.13 0)
		(unit 1)
		(exclude_from_sim no)
		(in_bom yes)
		(on_board yes)
		(dnp no)
		(property "Reference" "#PWR053"
			(at 336.55 153.67 0)
			(effects
				(font
					(size 1.27 1.27)
					(thickness 0.15)
				)
				(justify left bottom)
				(hide yes)
			)
		)
		(property "Value" "GND"
			(at 327.66 154.94 0)
			(effects
				(font
					(size 1.27 1.27)
					(thickness 0.15)
				)
			)
		)
		(property "Footprint" ""
			(at 336.55 158.75 0)
			(effects
				(font
					(size 1.27 1.27)
					(thickness 0.15)
				)
				(justify left bottom)
				(hide yes)
			)
		)
		(property "Datasheet" ""
			(at 336.55 163.83 0)
			(effects
				(font
					(size 1.27 1.27)
					(thickness 0.15)
				)
				(justify left bottom)
				(hide yes)
			)
		)
		(property "Description" ""
			(at 327.66 151.13 0)
			(effects
				(font
					(size 1.27 1.27)
				)
				(hide yes)
			)
		)
		(property "Author" "Antmicro"
			(at 336.55 158.75 0)
			(effects
				(font
					(size 1.27 1.27)
					(thickness 0.15)
				)
				(justify left bottom)
				(hide yes)
			)
		)
		(property "License" "Apache-2.0"
			(at 336.55 161.29 0)
			(effects
				(font
					(size 1.27 1.27)
					(thickness 0.15)
				)
				(justify left bottom)
				(hide yes)
			)
		)
		(pin "1"
		)
		(instances
			(project "gmsl-deserializer"
				(path ""
					(reference "#PWR053")
					(unit 1)
				)
			)
		)
	)
	(symbol
		(lib_id "antmicropower:GND")
		(at 388.62 161.29 0)
		(unit 1)
		(exclude_from_sim no)
		(in_bom yes)
		(on_board yes)
		(dnp no)
		(property "Reference" "#PWR0124"
			(at 397.51 163.83 0)
			(effects
				(font
					(size 1.27 1.27)
					(thickness 0.15)
				)
				(justify left bottom)
				(hide yes)
			)
		)
		(property "Value" "GND"
			(at 388.62 165.1 0)
			(effects
				(font
					(size 1.27 1.27)
					(thickness 0.15)
				)
			)
		)
		(property "Footprint" ""
			(at 397.51 168.91 0)
			(effects
				(font
					(size 1.27 1.27)
					(thickness 0.15)
				)
				(justify left bottom)
				(hide yes)
			)
		)
		(property "Datasheet" ""
			(at 397.51 173.99 0)
			(effects
				(font
					(size 1.27 1.27)
					(thickness 0.15)
				)
				(justify left bottom)
				(hide yes)
			)
		)
		(property "Description" ""
			(at 388.62 161.29 0)
			(effects
				(font
					(size 1.27 1.27)
				)
				(hide yes)
			)
		)
		(property "Author" "Antmicro"
			(at 397.51 168.91 0)
			(effects
				(font
					(size 1.27 1.27)
					(thickness 0.15)
				)
				(justify left bottom)
				(hide yes)
			)
		)
		(property "License" "Apache-2.0"
			(at 397.51 171.45 0)
			(effects
				(font
					(size 1.27 1.27)
					(thickness 0.15)
				)
				(justify left bottom)
				(hide yes)
			)
		)
		(pin "1"
		)
		(instances
			(project "gmsl-deserializer"
				(path ""
					(reference "#PWR0124")
					(unit 1)
				)
			)
		)
	)
	(symbol
		(lib_id "antmicroCapacitors0402:C_22u_0402")
		(at 349.25 72.39 90)
		(unit 1)
		(exclude_from_sim no)
		(in_bom yes)
		(on_board yes)
		(dnp no)
		(fields_autoplaced yes)
		(property "Reference" "C24"
			(at 352.425 68.5735 90)
			(effects
				(font
					(size 1.27 1.27)
					(thickness 0.15)
				)
				(justify right)
			)
		)
		(property "Value" "C_22u_0402"
			(at 359.41 52.07 0)
			(effects
				(font
					(size 1.27 1.27)
					(thickness 0.15)
				)
				(justify left bottom)
				(hide yes)
			)
		)
		(property "Footprint" "antmicro-footprints:C_0402_1005Metric"
			(at 361.95 52.07 0)
			(effects
				(font
					(size 1.27 1.27)
					(thickness 0.15)
				)
				(justify left bottom)
				(hide yes)
			)
		)
		(property "Datasheet" "https://www.murata.com/products/productdetail?partno=GRM158R60J226ME01%23"
			(at 364.49 52.07 0)
			(effects
				(font
					(size 1.27 1.27)
					(thickness 0.15)
				)
				(justify left bottom)
				(hide yes)
			)
		)
		(property "Description" "SMD Multilayer Ceramic Capacitor, 22 uF, 4 V, 0402 [1005 Metric], X6S"
			(at 349.25 72.39 0)
			(effects
				(font
					(size 1.27 1.27)
				)
				(hide yes)
			)
		)
		(property "MPN" "GRM158R60J226ME01D"
			(at 367.03 52.07 0)
			(effects
				(font
					(size 1.27 1.27)
					(thickness 0.15)
				)
				(justify left bottom)
				(hide yes)
			)
		)
		(property "Manufacturer" "Murata"
			(at 369.57 52.07 0)
			(effects
				(font
					(size 1.27 1.27)
					(thickness 0.15)
				)
				(justify left bottom)
				(hide yes)
			)
		)
		(property "License" "Apache-2.0"
			(at 372.11 52.07 0)
			(effects
				(font
					(size 1.27 1.27)
					(thickness 0.15)
				)
				(justify left bottom)
				(hide yes)
			)
		)
		(property "Author" "Antmicro"
			(at 374.65 52.07 0)
			(effects
				(font
					(size 1.27 1.27)
					(thickness 0.15)
				)
				(justify left bottom)
				(hide yes)
			)
		)
		(property "Val" "22u"
			(at 352.425 71.1135 90)
			(effects
				(font
					(size 1.27 1.27)
					(thickness 0.15)
				)
				(justify right)
			)
		)
		(property "Voltage" ""
			(at 377.19 52.07 0)
			(effects
				(font
					(size 1.27 1.27)
				)
				(justify left bottom)
				(hide yes)
			)
		)
		(property "Dielectric" ""
			(at 379.73 52.07 0)
			(effects
				(font
					(size 1.27 1.27)
				)
				(justify left bottom)
				(hide yes)
			)
		)
		(pin "1"
		)
		(pin "2"
		)
		(instances
			(project "gmsl-deserializer"
				(path ""
					(reference "C24")
					(unit 1)
				)
			)
		)
	)
	(symbol
		(lib_id "antmicroResistors0603:R_0R_22.4A_0603")
		(at 88.9 210.82 0)
		(unit 1)
		(exclude_from_sim no)
		(in_bom no)
		(on_board yes)
		(dnp yes)
		(property "Reference" "R18"
			(at 91.44 205.74 0)
			(effects
				(font
					(size 1.27 1.27)
					(thickness 0.15)
				)
			)
		)
		(property "Value" "R_0R_22.4A_0603"
			(at 91.44 205.105 0)
			(effects
				(font
					(size 1.27 1.27)
					(thickness 0.15)
				)
				(hide yes)
			)
		)
		(property "Footprint" "antmicro-footprints:R_0603_1608Metric"
			(at 104.14 220.98 0)
			(effects
				(font
					(size 1.27 1.27)
					(thickness 0.15)
				)
				(justify left bottom)
				(hide yes)
			)
		)
		(property "Datasheet" "https://fscdn.rohm.com/en/products/databook/datasheet/passive/resistor/chip_resistor/pmr-jpw-e.pdf"
			(at 104.14 223.52 0)
			(effects
				(font
					(size 1.27 1.27)
					(thickness 0.15)
				)
				(justify left bottom)
				(hide yes)
			)
		)
		(property "Description" "SMD Chip Resistor"
			(at 88.9 210.82 0)
			(effects
				(font
					(size 1.27 1.27)
				)
				(hide yes)
			)
		)
		(property "MPN" "PMR03EZPJ000"
			(at 104.14 226.06 0)
			(effects
				(font
					(size 1.27 1.27)
					(thickness 0.15)
				)
				(justify left bottom)
				(hide yes)
			)
		)
		(property "Manufacturer" "ROHM Semiconductor"
			(at 104.14 228.6 0)
			(effects
				(font
					(size 1.27 1.27)
					(thickness 0.15)
				)
				(justify left bottom)
				(hide yes)
			)
		)
		(property "Val" "0R"
			(at 91.44 208.28 0)
			(effects
				(font
					(size 1.27 1.27)
					(thickness 0.15)
				)
			)
		)
		(property "Max. Curr." "22.4A"
			(at 91.44 213.36 0)
			(effects
				(font
					(size 1.27 1.27)
					(thickness 0.15)
				)
			)
		)
		(property "Author" "Antmicro"
			(at 104.14 233.68 0)
			(effects
				(font
					(size 1.27 1.27)
					(thickness 0.15)
				)
				(justify left bottom)
				(hide yes)
			)
		)
		(property "License" "Apache-2.0"
			(at 104.14 236.22 0)
			(effects
				(font
					(size 1.27 1.27)
					(thickness 0.15)
				)
				(justify left bottom)
				(hide yes)
			)
		)
		(property "Tolerance" "template_tolerance"
			(at 109.22 220.98 0)
			(effects
				(font
					(size 1.27 1.27)
				)
				(justify left bottom)
				(hide yes)
			)
		)
		(pin "1"
		)
		(pin "2"
		)
		(instances
			(project "gmsl-deserializer"
				(path ""
					(reference "R18")
					(unit 1)
				)
			)
		)
	)
	(symbol
		(lib_id "antmicropower:GND")
		(at 287.02 67.31 0)
		(unit 1)
		(exclude_from_sim no)
		(in_bom yes)
		(on_board yes)
		(dnp no)
		(property "Reference" "#PWR048"
			(at 295.91 69.85 0)
			(effects
				(font
					(size 1.27 1.27)
					(thickness 0.15)
				)
				(justify left bottom)
				(hide yes)
			)
		)
		(property "Value" "GND"
			(at 287.02 71.12 0)
			(effects
				(font
					(size 1.27 1.27)
					(thickness 0.15)
				)
			)
		)
		(property "Footprint" ""
			(at 295.91 74.93 0)
			(effects
				(font
					(size 1.27 1.27)
					(thickness 0.15)
				)
				(justify left bottom)
				(hide yes)
			)
		)
		(property "Datasheet" ""
			(at 295.91 80.01 0)
			(effects
				(font
					(size 1.27 1.27)
					(thickness 0.15)
				)
				(justify left bottom)
				(hide yes)
			)
		)
		(property "Description" ""
			(at 287.02 67.31 0)
			(effects
				(font
					(size 1.27 1.27)
				)
				(hide yes)
			)
		)
		(property "Author" "Antmicro"
			(at 295.91 74.93 0)
			(effects
				(font
					(size 1.27 1.27)
					(thickness 0.15)
				)
				(justify left bottom)
				(hide yes)
			)
		)
		(property "License" "Apache-2.0"
			(at 295.91 77.47 0)
			(effects
				(font
					(size 1.27 1.27)
					(thickness 0.15)
				)
				(justify left bottom)
				(hide yes)
			)
		)
		(pin "1"
		)
		(instances
			(project "gmsl-deserializer"
				(path ""
					(reference "#PWR048")
					(unit 1)
				)
			)
		)
	)
	(symbol
		(lib_id "antmicroResistors0402:R_100k_0402")
		(at 375.92 158.75 90)
		(unit 1)
		(exclude_from_sim no)
		(in_bom yes)
		(on_board yes)
		(dnp no)
		(fields_autoplaced yes)
		(property "Reference" "R72"
			(at 378.46 154.9399 90)
			(effects
				(font
					(size 1.27 1.27)
					(thickness 0.15)
				)
				(justify right)
			)
		)
		(property "Value" "R_100k_0402"
			(at 388.62 138.43 0)
			(effects
				(font
					(size 1.27 1.27)
					(thickness 0.15)
				)
				(justify left bottom)
				(hide yes)
			)
		)
		(property "Footprint" "antmicro-footprints:R_0402_1005Metric"
			(at 391.16 138.43 0)
			(effects
				(font
					(size 1.27 1.27)
					(thickness 0.15)
				)
				(justify left bottom)
				(hide yes)
			)
		)
		(property "Datasheet" "https://www.bourns.com/docs/product-datasheets/cr.pdf"
			(at 393.7 138.43 0)
			(effects
				(font
					(size 1.27 1.27)
					(thickness 0.15)
				)
				(justify left bottom)
				(hide yes)
			)
		)
		(property "Description" "SMD Chip Resistor, 100 kohm, ± 1%, 62.5 mW, 0402 [1005 Metric], Thick Film, General Purpose"
			(at 375.92 158.75 0)
			(effects
				(font
					(size 1.27 1.27)
				)
				(hide yes)
			)
		)
		(property "MPN" "CR0402-FX-1003GLF"
			(at 396.24 138.43 0)
			(effects
				(font
					(size 1.27 1.27)
					(thickness 0.15)
				)
				(justify left bottom)
				(hide yes)
			)
		)
		(property "Manufacturer" "Bourns"
			(at 398.78 138.43 0)
			(effects
				(font
					(size 1.27 1.27)
					(thickness 0.15)
				)
				(justify left bottom)
				(hide yes)
			)
		)
		(property "License" "Apache-2.0"
			(at 401.32 138.43 0)
			(effects
				(font
					(size 1.27 1.27)
					(thickness 0.15)
				)
				(justify left bottom)
				(hide yes)
			)
		)
		(property "Author" "Antmicro"
			(at 403.86 138.43 0)
			(effects
				(font
					(size 1.27 1.27)
					(thickness 0.15)
				)
				(justify left bottom)
				(hide yes)
			)
		)
		(property "Val" "100k"
			(at 378.46 157.4799 90)
			(effects
				(font
					(size 1.27 1.27)
					(thickness 0.15)
				)
				(justify right)
			)
		)
		(property "Tolerance" "1%"
			(at 386.08 138.43 0)
			(effects
				(font
					(size 1.27 1.27)
				)
				(justify left bottom)
				(hide yes)
			)
		)
		(pin "1"
		)
		(pin "2"
		)
		(instances
			(project "gmsl-deserializer"
				(path ""
					(reference "R72")
					(unit 1)
				)
			)
		)
	)
	(symbol
		(lib_id "antmicroDCDCConverters:LMR62014XMF")
		(at 199.39 232.41 0)
		(unit 1)
		(exclude_from_sim no)
		(in_bom yes)
		(on_board yes)
		(dnp no)
		(fields_autoplaced yes)
		(property "Reference" "U3"
			(at 207.01 224.155 0)
			(effects
				(font
					(size 1.27 1.27)
					(thickness 0.15)
				)
			)
		)
		(property "Value" "LMR62014XMF"
			(at 229.87 240.03 0)
			(effects
				(font
					(size 1.27 1.27)
					(thickness 0.15)
				)
				(justify left bottom)
				(hide yes)
			)
		)
		(property "Footprint" "antmicro-footprints:SOT-23-5"
			(at 229.87 242.57 0)
			(effects
				(font
					(size 1.27 1.27)
					(thickness 0.15)
				)
				(justify left bottom)
				(hide yes)
			)
		)
		(property "Datasheet" "https://www.ti.com/lit/ds/symlink/lmr62014.pdf?ts=1698148381034"
			(at 229.87 245.11 0)
			(effects
				(font
					(size 1.27 1.27)
					(thickness 0.15)
				)
				(justify left bottom)
				(hide yes)
			)
		)
		(property "Description" "Step-Up Regulator  2.7V to 14V, 1.4A"
			(at 199.39 232.41 0)
			(effects
				(font
					(size 1.27 1.27)
				)
				(hide yes)
			)
		)
		(property "Manufacturer" "Texas Instruments"
			(at 229.87 247.65 0)
			(effects
				(font
					(size 1.27 1.27)
					(thickness 0.15)
				)
				(justify left bottom)
				(hide yes)
			)
		)
		(property "MPN" "LMR62014XMF/NOPB"
			(at 207.01 226.695 0)
			(effects
				(font
					(size 1.27 1.27)
					(thickness 0.15)
				)
			)
		)
		(property "Author" "Antmicro"
			(at 229.87 250.19 0)
			(effects
				(font
					(size 1.27 1.27)
					(thickness 0.15)
				)
				(justify left bottom)
				(hide yes)
			)
		)
		(property "License" "Apache-2.0"
			(at 229.87 252.73 0)
			(effects
				(font
					(size 1.27 1.27)
					(thickness 0.15)
				)
				(justify left bottom)
				(hide yes)
			)
		)
		(pin "1"
		)
		(pin "2"
		)
		(pin "3"
		)
		(pin "4"
		)
		(pin "5"
		)
		(instances
			(project "gmsl-deserializer"
				(path ""
					(reference "U3")
					(unit 1)
				)
			)
		)
	)
	(symbol
		(lib_id "antmicroFixedInductors:L_10u_3.1A_Bourns-SRN8040")
		(at 204.47 220.98 0)
		(unit 1)
		(exclude_from_sim no)
		(in_bom yes)
		(on_board yes)
		(dnp no)
		(fields_autoplaced yes)
		(property "Reference" "L17"
			(at 207.01 215.265 0)
			(effects
				(font
					(size 1.27 1.27)
					(thickness 0.15)
				)
			)
		)
		(property "Value" "L_10u_3.1A_Bourns-SRN8040"
			(at 218.44 223.52 0)
			(effects
				(font
					(size 1.27 1.27)
					(thickness 0.15)
				)
				(justify left bottom)
				(hide yes)
			)
		)
		(property "Footprint" "antmicro-footprints:L_Bourns-SRN8040"
			(at 218.44 228.6 0)
			(effects
				(font
					(size 1.27 1.27)
					(thickness 0.15)
				)
				(justify left bottom)
				(hide yes)
			)
		)
		(property "Datasheet" "https://www.bourns.com/pdfs/SRN8040.pdf"
			(at 218.44 231.14 0)
			(effects
				(font
					(size 1.27 1.27)
					(thickness 0.15)
				)
				(justify left bottom)
				(hide yes)
			)
		)
		(property "Description" "Power Inductor (SMD), 10 µH, 3.1 A, Shielded, 3.4 A, SRN8040"
			(at 204.47 220.98 0)
			(effects
				(font
					(size 1.27 1.27)
				)
				(hide yes)
			)
		)
		(property "Val" "10u/3.1A"
			(at 207.01 217.805 0)
			(effects
				(font
					(size 1.27 1.27)
					(thickness 0.15)
				)
			)
		)
		(property "Manufacturer" "Bourns"
			(at 218.44 233.68 0)
			(effects
				(font
					(size 1.27 1.27)
					(thickness 0.15)
				)
				(justify left bottom)
				(hide yes)
			)
		)
		(property "MPN" "SRN8040-100M"
			(at 218.44 236.22 0)
			(effects
				(font
					(size 1.27 1.27)
					(thickness 0.15)
				)
				(justify left bottom)
				(hide yes)
			)
		)
		(property "ISat" "3.4 A"
			(at 218.44 237.49 0)
			(effects
				(font
					(size 1.27 1.27)
				)
				(justify left)
				(hide yes)
			)
		)
		(property "IMax" "3.1 A"
			(at 218.44 241.3 0)
			(effects
				(font
					(size 1.27 1.27)
					(thickness 0.15)
				)
				(justify left bottom)
				(hide yes)
			)
		)
		(property "Size" "8.0x8.0"
			(at 218.44 243.84 0)
			(effects
				(font
					(size 1.27 1.27)
					(thickness 0.15)
				)
				(justify left bottom)
				(hide yes)
			)
		)
		(property "Author" "Antmicro"
			(at 218.44 246.38 0)
			(effects
				(font
					(size 1.27 1.27)
					(thickness 0.15)
				)
				(justify left bottom)
				(hide yes)
			)
		)
		(property "License" "Apache-2.0"
			(at 218.44 248.92 0)
			(effects
				(font
					(size 1.27 1.27)
					(thickness 0.15)
				)
				(justify left bottom)
				(hide yes)
			)
		)
		(pin "1"
		)
		(pin "2"
		)
		(instances
			(project "gmsl-deserializer"
				(path ""
					(reference "L17")
					(unit 1)
				)
			)
		)
	)
	(symbol
		(lib_id "antmicropower:GND")
		(at 340.36 151.13 0)
		(unit 1)
		(exclude_from_sim no)
		(in_bom yes)
		(on_board yes)
		(dnp no)
		(property "Reference" "#PWR055"
			(at 349.25 153.67 0)
			(effects
				(font
					(size 1.27 1.27)
					(thickness 0.15)
				)
				(justify left bottom)
				(hide yes)
			)
		)
		(property "Value" "GND"
			(at 340.36 154.94 0)
			(effects
				(font
					(size 1.27 1.27)
					(thickness 0.15)
				)
			)
		)
		(property "Footprint" ""
			(at 349.25 158.75 0)
			(effects
				(font
					(size 1.27 1.27)
					(thickness 0.15)
				)
				(justify left bottom)
				(hide yes)
			)
		)
		(property "Datasheet" ""
			(at 349.25 163.83 0)
			(effects
				(font
					(size 1.27 1.27)
					(thickness 0.15)
				)
				(justify left bottom)
				(hide yes)
			)
		)
		(property "Description" ""
			(at 340.36 151.13 0)
			(effects
				(font
					(size 1.27 1.27)
				)
				(hide yes)
			)
		)
		(property "Author" "Antmicro"
			(at 349.25 158.75 0)
			(effects
				(font
					(size 1.27 1.27)
					(thickness 0.15)
				)
				(justify left bottom)
				(hide yes)
			)
		)
		(property "License" "Apache-2.0"
			(at 349.25 161.29 0)
			(effects
				(font
					(size 1.27 1.27)
					(thickness 0.15)
				)
				(justify left bottom)
				(hide yes)
			)
		)
		(pin "1"
		)
		(instances
			(project "gmsl-deserializer"
				(path ""
					(reference "#PWR055")
					(unit 1)
				)
			)
		)
	)
	(symbol
		(lib_id "antmicropower:GND")
		(at 81.28 123.19 0)
		(unit 1)
		(exclude_from_sim no)
		(in_bom yes)
		(on_board yes)
		(dnp no)
		(property "Reference" "#PWR027"
			(at 90.17 125.73 0)
			(effects
				(font
					(size 1.27 1.27)
					(thickness 0.15)
				)
				(justify left bottom)
				(hide yes)
			)
		)
		(property "Value" "GND"
			(at 81.28 127 0)
			(effects
				(font
					(size 1.27 1.27)
					(thickness 0.15)
				)
			)
		)
		(property "Footprint" ""
			(at 90.17 130.81 0)
			(effects
				(font
					(size 1.27 1.27)
					(thickness 0.15)
				)
				(justify left bottom)
				(hide yes)
			)
		)
		(property "Datasheet" ""
			(at 90.17 135.89 0)
			(effects
				(font
					(size 1.27 1.27)
					(thickness 0.15)
				)
				(justify left bottom)
				(hide yes)
			)
		)
		(property "Description" ""
			(at 81.28 123.19 0)
			(effects
				(font
					(size 1.27 1.27)
				)
				(hide yes)
			)
		)
		(property "Author" "Antmicro"
			(at 90.17 130.81 0)
			(effects
				(font
					(size 1.27 1.27)
					(thickness 0.15)
				)
				(justify left bottom)
				(hide yes)
			)
		)
		(property "License" "Apache-2.0"
			(at 90.17 133.35 0)
			(effects
				(font
					(size 1.27 1.27)
					(thickness 0.15)
				)
				(justify left bottom)
				(hide yes)
			)
		)
		(pin "1"
		)
		(instances
			(project "gmsl-deserializer"
				(path ""
					(reference "#PWR027")
					(unit 1)
				)
			)
		)
	)
	(symbol
		(lib_id "antmicroPMICORControllersIdealDiodes:DZDH0401DW")
		(at 82.55 238.76 0)
		(unit 1)
		(exclude_from_sim no)
		(in_bom yes)
		(on_board yes)
		(dnp no)
		(property "Reference" "Q3"
			(at 90.17 232.41 0)
			(effects
				(font
					(size 1.27 1.27)
					(thickness 0.15)
				)
			)
		)
		(property "Value" "DZDH0401DW"
			(at 91.44 234.95 0)
			(effects
				(font
					(size 1.27 1.27)
					(thickness 0.15)
				)
			)
		)
		(property "Footprint" "antmicro-footprints:SOT-363"
			(at 113.03 248.92 0)
			(effects
				(font
					(size 1.27 1.27)
					(thickness 0.15)
				)
				(justify left bottom)
				(hide yes)
			)
		)
		(property "Datasheet" "https://www.mouser.com/datasheet/2/115/DIOD_S_A0011803041_1-2543705.pdf"
			(at 113.03 251.46 0)
			(effects
				(font
					(size 1.27 1.27)
					(thickness 0.15)
				)
				(justify left bottom)
				(hide yes)
			)
		)
		(property "Description" "OR Controller N+1 ORing Controller P-Channel 1:1 SOT-363"
			(at 82.55 238.76 0)
			(effects
				(font
					(size 1.27 1.27)
				)
				(hide yes)
			)
		)
		(property "MPN" "DZDH0401DW"
			(at 113.03 254 0)
			(effects
				(font
					(size 1.27 1.27)
					(thickness 0.15)
				)
				(justify left bottom)
				(hide yes)
			)
		)
		(property "Manufacturer" "Diodes Incorporated"
			(at 113.03 256.54 0)
			(effects
				(font
					(size 1.27 1.27)
					(thickness 0.15)
				)
				(justify left bottom)
				(hide yes)
			)
		)
		(property "Author" "Antmicro"
			(at 113.03 259.08 0)
			(effects
				(font
					(size 1.27 1.27)
					(thickness 0.15)
				)
				(justify left bottom)
				(hide yes)
			)
		)
		(property "License" "Apache-2.0"
			(at 113.03 261.62 0)
			(effects
				(font
					(size 1.27 1.27)
					(thickness 0.15)
				)
				(justify left bottom)
				(hide yes)
			)
		)
		(pin "2"
		)
		(pin "3"
		)
		(pin "4"
		)
		(pin "6"
		)
		(pin "1"
		)
		(pin "5"
		)
		(instances
			(project "gmsl-deserializer"
				(path ""
					(reference "Q3")
					(unit 1)
				)
			)
		)
	)
	(symbol
		(lib_id "antmicroResistors0402:R_13k7_0402")
		(at 217.17 250.19 90)
		(unit 1)
		(exclude_from_sim no)
		(in_bom yes)
		(on_board yes)
		(dnp no)
		(fields_autoplaced yes)
		(property "Reference" "R29"
			(at 219.075 246.3799 90)
			(effects
				(font
					(size 1.27 1.27)
					(thickness 0.15)
				)
				(justify right)
			)
		)
		(property "Value" "R_13k7_0402"
			(at 229.87 229.87 0)
			(effects
				(font
					(size 1.27 1.27)
					(thickness 0.15)
				)
				(justify left bottom)
				(hide yes)
			)
		)
		(property "Footprint" "antmicro-footprints:R_0402_1005Metric"
			(at 232.41 229.87 0)
			(effects
				(font
					(size 1.27 1.27)
					(thickness 0.15)
				)
				(justify left bottom)
				(hide yes)
			)
		)
		(property "Datasheet" "https://www.bourns.com/docs/product-datasheets/cr.pdf"
			(at 234.95 229.87 0)
			(effects
				(font
					(size 1.27 1.27)
					(thickness 0.15)
				)
				(justify left bottom)
				(hide yes)
			)
		)
		(property "Description" "SMD Chip Resistor, Ceramic, 13.7 kohm, ± 1%, 62.5 mW, 0402 [1005 Metric], Thick Film"
			(at 217.17 250.19 0)
			(effects
				(font
					(size 1.27 1.27)
				)
				(hide yes)
			)
		)
		(property "MPN" "CR0402-FX-1372GLF"
			(at 237.49 229.87 0)
			(effects
				(font
					(size 1.27 1.27)
					(thickness 0.15)
				)
				(justify left bottom)
				(hide yes)
			)
		)
		(property "Manufacturer" "Bourns"
			(at 240.03 229.87 0)
			(effects
				(font
					(size 1.27 1.27)
					(thickness 0.15)
				)
				(justify left bottom)
				(hide yes)
			)
		)
		(property "License" "Apache-2.0"
			(at 242.57 229.87 0)
			(effects
				(font
					(size 1.27 1.27)
					(thickness 0.15)
				)
				(justify left bottom)
				(hide yes)
			)
		)
		(property "Author" "Antmicro"
			(at 245.11 229.87 0)
			(effects
				(font
					(size 1.27 1.27)
					(thickness 0.15)
				)
				(justify left bottom)
				(hide yes)
			)
		)
		(property "Val" "13k7"
			(at 219.075 248.9199 90)
			(effects
				(font
					(size 1.27 1.27)
					(thickness 0.15)
				)
				(justify right)
			)
		)
		(property "Tolerance" "1%"
			(at 227.33 229.87 0)
			(effects
				(font
					(size 1.27 1.27)
				)
				(justify left bottom)
				(hide yes)
			)
		)
		(pin "1"
		)
		(pin "2"
		)
		(instances
			(project "gmsl-deserializer"
				(path ""
					(reference "R29")
					(unit 1)
				)
			)
		)
	)
	(symbol
		(lib_id "antmicropower:GND")
		(at 88.9 97.79 0)
		(unit 1)
		(exclude_from_sim no)
		(in_bom yes)
		(on_board yes)
		(dnp no)
		(property "Reference" "#PWR031"
			(at 97.79 100.33 0)
			(effects
				(font
					(size 1.27 1.27)
					(thickness 0.15)
				)
				(justify left bottom)
				(hide yes)
			)
		)
		(property "Value" "GND"
			(at 88.9 101.6 0)
			(effects
				(font
					(size 1.27 1.27)
					(thickness 0.15)
				)
			)
		)
		(property "Footprint" ""
			(at 97.79 105.41 0)
			(effects
				(font
					(size 1.27 1.27)
					(thickness 0.15)
				)
				(justify left bottom)
				(hide yes)
			)
		)
		(property "Datasheet" ""
			(at 97.79 110.49 0)
			(effects
				(font
					(size 1.27 1.27)
					(thickness 0.15)
				)
				(justify left bottom)
				(hide yes)
			)
		)
		(property "Description" ""
			(at 88.9 97.79 0)
			(effects
				(font
					(size 1.27 1.27)
				)
				(hide yes)
			)
		)
		(property "Author" "Antmicro"
			(at 97.79 105.41 0)
			(effects
				(font
					(size 1.27 1.27)
					(thickness 0.15)
				)
				(justify left bottom)
				(hide yes)
			)
		)
		(property "License" "Apache-2.0"
			(at 97.79 107.95 0)
			(effects
				(font
					(size 1.27 1.27)
					(thickness 0.15)
				)
				(justify left bottom)
				(hide yes)
			)
		)
		(pin "1"
		)
		(instances
			(project "gmsl-deserializer"
				(path ""
					(reference "#PWR031")
					(unit 1)
				)
			)
		)
	)
	(symbol
		(lib_id "antmicroResistors0603:R_0R_22.4A_0603")
		(at 259.08 232.41 0)
		(unit 1)
		(exclude_from_sim no)
		(in_bom yes)
		(on_board yes)
		(dnp no)
		(property "Reference" "R62"
			(at 261.62 227.33 0)
			(effects
				(font
					(size 1.27 1.27)
					(thickness 0.15)
				)
			)
		)
		(property "Value" "R_0R_22.4A_0603"
			(at 261.62 226.695 0)
			(effects
				(font
					(size 1.27 1.27)
					(thickness 0.15)
				)
				(hide yes)
			)
		)
		(property "Footprint" "antmicro-footprints:R_0603_1608Metric"
			(at 274.32 242.57 0)
			(effects
				(font
					(size 1.27 1.27)
					(thickness 0.15)
				)
				(justify left bottom)
				(hide yes)
			)
		)
		(property "Datasheet" "https://fscdn.rohm.com/en/products/databook/datasheet/passive/resistor/chip_resistor/pmr-jpw-e.pdf"
			(at 274.32 245.11 0)
			(effects
				(font
					(size 1.27 1.27)
					(thickness 0.15)
				)
				(justify left bottom)
				(hide yes)
			)
		)
		(property "Description" "SMD Chip Resistor"
			(at 259.08 232.41 0)
			(effects
				(font
					(size 1.27 1.27)
				)
				(hide yes)
			)
		)
		(property "MPN" "PMR03EZPJ000"
			(at 274.32 247.65 0)
			(effects
				(font
					(size 1.27 1.27)
					(thickness 0.15)
				)
				(justify left bottom)
				(hide yes)
			)
		)
		(property "Manufacturer" "ROHM Semiconductor"
			(at 274.32 250.19 0)
			(effects
				(font
					(size 1.27 1.27)
					(thickness 0.15)
				)
				(justify left bottom)
				(hide yes)
			)
		)
		(property "Val" "0R"
			(at 261.62 229.87 0)
			(effects
				(font
					(size 1.27 1.27)
					(thickness 0.15)
				)
			)
		)
		(property "Max. Curr." "22.4A"
			(at 261.62 234.95 0)
			(effects
				(font
					(size 1.27 1.27)
					(thickness 0.15)
				)
			)
		)
		(property "Author" "Antmicro"
			(at 274.32 255.27 0)
			(effects
				(font
					(size 1.27 1.27)
					(thickness 0.15)
				)
				(justify left bottom)
				(hide yes)
			)
		)
		(property "License" "Apache-2.0"
			(at 274.32 257.81 0)
			(effects
				(font
					(size 1.27 1.27)
					(thickness 0.15)
				)
				(justify left bottom)
				(hide yes)
			)
		)
		(property "Tolerance" "template_tolerance"
			(at 279.4 242.57 0)
			(effects
				(font
					(size 1.27 1.27)
				)
				(justify left bottom)
				(hide yes)
			)
		)
		(pin "1"
		)
		(pin "2"
		)
		(instances
			(project "gmsl-deserializer"
				(path ""
					(reference "R62")
					(unit 1)
				)
			)
		)
	)
	(symbol
		(lib_id "antmicropower:GND")
		(at 88.9 149.86 0)
		(unit 1)
		(exclude_from_sim no)
		(in_bom yes)
		(on_board yes)
		(dnp no)
		(property "Reference" "#PWR033"
			(at 97.79 152.4 0)
			(effects
				(font
					(size 1.27 1.27)
					(thickness 0.15)
				)
				(justify left bottom)
				(hide yes)
			)
		)
		(property "Value" "GND"
			(at 88.9 153.67 0)
			(effects
				(font
					(size 1.27 1.27)
					(thickness 0.15)
				)
			)
		)
		(property "Footprint" ""
			(at 97.79 157.48 0)
			(effects
				(font
					(size 1.27 1.27)
					(thickness 0.15)
				)
				(justify left bottom)
				(hide yes)
			)
		)
		(property "Datasheet" ""
			(at 97.79 162.56 0)
			(effects
				(font
					(size 1.27 1.27)
					(thickness 0.15)
				)
				(justify left bottom)
				(hide yes)
			)
		)
		(property "Description" ""
			(at 88.9 149.86 0)
			(effects
				(font
					(size 1.27 1.27)
				)
				(hide yes)
			)
		)
		(property "Author" "Antmicro"
			(at 97.79 157.48 0)
			(effects
				(font
					(size 1.27 1.27)
					(thickness 0.15)
				)
				(justify left bottom)
				(hide yes)
			)
		)
		(property "License" "Apache-2.0"
			(at 97.79 160.02 0)
			(effects
				(font
					(size 1.27 1.27)
					(thickness 0.15)
				)
				(justify left bottom)
				(hide yes)
			)
		)
		(pin "1"
		)
		(instances
			(project "gmsl-deserializer"
				(path ""
					(reference "#PWR033")
					(unit 1)
				)
			)
		)
	)
	(symbol
		(lib_id "antmicropower:+12V")
		(at 279.4 44.45 0)
		(unit 1)
		(exclude_from_sim no)
		(in_bom yes)
		(on_board yes)
		(dnp no)
		(fields_autoplaced yes)
		(property "Reference" "#PWR047"
			(at 279.4 48.26 0)
			(effects
				(font
					(size 1.27 1.27)
				)
				(hide yes)
			)
		)
		(property "Value" "+12V"
			(at 279.4 39.37 0)
			(effects
				(font
					(size 1.27 1.27)
				)
			)
		)
		(property "Footprint" ""
			(at 279.4 44.45 0)
			(effects
				(font
					(size 1.27 1.27)
				)
				(hide yes)
			)
		)
		(property "Datasheet" ""
			(at 279.4 44.45 0)
			(effects
				(font
					(size 1.27 1.27)
				)
				(hide yes)
			)
		)
		(property "Description" ""
			(at 279.4 44.45 0)
			(effects
				(font
					(size 1.27 1.27)
				)
				(hide yes)
			)
		)
		(pin "1"
		)
		(instances
			(project "gmsl-deserializer"
				(path ""
					(reference "#PWR047")
					(unit 1)
				)
			)
		)
	)
	(symbol
		(lib_id "antmicroCapacitors0402:C_100n_0402")
		(at 81.28 71.12 90)
		(unit 1)
		(exclude_from_sim no)
		(in_bom yes)
		(on_board yes)
		(dnp no)
		(property "Reference" "C6"
			(at 81.915 66.675 90)
			(effects
				(font
					(size 1.27 1.27)
					(thickness 0.15)
				)
				(justify right)
			)
		)
		(property "Value" "C_100n_0402"
			(at 91.44 50.8 0)
			(effects
				(font
					(size 1.27 1.27)
					(thickness 0.15)
				)
				(justify left bottom)
				(hide yes)
			)
		)
		(property "Footprint" "antmicro-footprints:C_0402_1005Metric"
			(at 93.98 50.8 0)
			(effects
				(font
					(size 1.27 1.27)
					(thickness 0.15)
				)
				(justify left bottom)
				(hide yes)
			)
		)
		(property "Datasheet" "https://www.murata.com/products/productdetail?partno=GRM155R61H104KE14%23"
			(at 96.52 50.8 0)
			(effects
				(font
					(size 1.27 1.27)
					(thickness 0.15)
				)
				(justify left bottom)
				(hide yes)
			)
		)
		(property "Description" "SMD Multilayer Ceramic Capacitor, 0.1 µF, 50 V, 0402 [1005 Metric], ± 10%, X5R, GRM Series"
			(at 81.28 71.12 0)
			(effects
				(font
					(size 1.27 1.27)
				)
				(hide yes)
			)
		)
		(property "MPN" "GRM155R61H104KE14D"
			(at 99.06 50.8 0)
			(effects
				(font
					(size 1.27 1.27)
					(thickness 0.15)
				)
				(justify left bottom)
				(hide yes)
			)
		)
		(property "Manufacturer" "Murata"
			(at 101.6 50.8 0)
			(effects
				(font
					(size 1.27 1.27)
					(thickness 0.15)
				)
				(justify left bottom)
				(hide yes)
			)
		)
		(property "License" "Apache-2.0"
			(at 104.14 50.8 0)
			(effects
				(font
					(size 1.27 1.27)
					(thickness 0.15)
				)
				(justify left bottom)
				(hide yes)
			)
		)
		(property "Author" "Antmicro"
			(at 106.68 50.8 0)
			(effects
				(font
					(size 1.27 1.27)
					(thickness 0.15)
				)
				(justify left bottom)
				(hide yes)
			)
		)
		(property "Val" "100n"
			(at 81.915 70.485 90)
			(effects
				(font
					(size 1.27 1.27)
					(thickness 0.15)
				)
				(justify right)
			)
		)
		(property "Voltage" "50V"
			(at 109.22 50.8 0)
			(effects
				(font
					(size 1.27 1.27)
				)
				(justify left bottom)
				(hide yes)
			)
		)
		(property "Dielectric" "X5R"
			(at 111.76 50.8 0)
			(effects
				(font
					(size 1.27 1.27)
				)
				(justify left bottom)
				(hide yes)
			)
		)
		(pin "1"
		)
		(pin "2"
		)
		(instances
			(project "gmsl-deserializer"
				(path ""
					(reference "C6")
					(unit 1)
				)
			)
		)
	)
	(symbol
		(lib_id "antmicroResistors0402:R_10k_0402")
		(at 279.4 67.31 90)
		(unit 1)
		(exclude_from_sim no)
		(in_bom yes)
		(on_board yes)
		(dnp no)
		(fields_autoplaced yes)
		(property "Reference" "R64"
			(at 281.305 63.4999 90)
			(effects
				(font
					(size 1.27 1.27)
					(thickness 0.15)
				)
				(justify right)
			)
		)
		(property "Value" "R_10k_0402"
			(at 292.1 46.99 0)
			(effects
				(font
					(size 1.27 1.27)
					(thickness 0.15)
				)
				(justify left bottom)
				(hide yes)
			)
		)
		(property "Footprint" "antmicro-footprints:R_0402_1005Metric"
			(at 294.64 46.99 0)
			(effects
				(font
					(size 1.27 1.27)
					(thickness 0.15)
				)
				(justify left bottom)
				(hide yes)
			)
		)
		(property "Datasheet" "https://www.bourns.com/docs/product-datasheets/cr.pdf"
			(at 297.18 46.99 0)
			(effects
				(font
					(size 1.27 1.27)
					(thickness 0.15)
				)
				(justify left bottom)
				(hide yes)
			)
		)
		(property "Description" "SMD Chip Resistor, 10 kohm, ± 1%, 62.5 mW, 0402 [1005 Metric], Thick Film, General Purpose"
			(at 279.4 67.31 0)
			(effects
				(font
					(size 1.27 1.27)
				)
				(hide yes)
			)
		)
		(property "MPN" "CR0402-FX-1002GLF"
			(at 299.72 46.99 0)
			(effects
				(font
					(size 1.27 1.27)
					(thickness 0.15)
				)
				(justify left bottom)
				(hide yes)
			)
		)
		(property "Manufacturer" "Bourns"
			(at 302.26 46.99 0)
			(effects
				(font
					(size 1.27 1.27)
					(thickness 0.15)
				)
				(justify left bottom)
				(hide yes)
			)
		)
		(property "License" "Apache-2.0"
			(at 304.8 46.99 0)
			(effects
				(font
					(size 1.27 1.27)
					(thickness 0.15)
				)
				(justify left bottom)
				(hide yes)
			)
		)
		(property "Author" "Antmicro"
			(at 307.34 46.99 0)
			(effects
				(font
					(size 1.27 1.27)
					(thickness 0.15)
				)
				(justify left bottom)
				(hide yes)
			)
		)
		(property "Val" "10k"
			(at 281.305 66.0399 90)
			(effects
				(font
					(size 1.27 1.27)
					(thickness 0.15)
				)
				(justify right)
			)
		)
		(property "Tolerance" "1%"
			(at 289.56 46.99 0)
			(effects
				(font
					(size 1.27 1.27)
				)
				(justify left bottom)
				(hide yes)
			)
		)
		(pin "1"
		)
		(pin "2"
		)
		(instances
			(project "gmsl-deserializer"
				(path ""
					(reference "R64")
					(unit 1)
				)
			)
		)
	)
	(symbol
		(lib_id "antmicroTestPoints:TP_0.75mm_SMD")
		(at 370.84 130.81 90)
		(unit 1)
		(exclude_from_sim no)
		(in_bom yes)
		(on_board yes)
		(dnp no)
		(property "Reference" "TP27"
			(at 369.57 125.73 90)
			(effects
				(font
					(size 1.27 1.27)
					(thickness 0.15)
				)
				(justify right)
			)
		)
		(property "Value" "TP_0.75mm_SMD"
			(at 374.65 120.015 0)
			(effects
				(font
					(size 1.27 1.27)
					(thickness 0.15)
				)
				(justify left bottom)
				(hide yes)
			)
		)
		(property "Footprint" "antmicro-footprints:TP_SMD_0.75mm"
			(at 377.19 120.015 0)
			(effects
				(font
					(size 1.27 1.27)
					(thickness 0.15)
				)
				(justify left bottom)
				(hide yes)
			)
		)
		(property "Datasheet" ""
			(at 383.54 113.03 0)
			(effects
				(font
					(size 1.27 1.27)
					(thickness 0.15)
				)
				(justify left bottom)
				(hide yes)
			)
		)
		(property "Description" "SMT test point"
			(at 370.84 130.81 0)
			(effects
				(font
					(size 1.27 1.27)
				)
				(hide yes)
			)
		)
		(property "MPN" ""
			(at 382.27 120.015 0)
			(effects
				(font
					(size 1.27 1.27)
					(thickness 0.15)
				)
				(justify left bottom)
				(hide yes)
			)
		)
		(property "Manufacturer" ""
			(at 377.19 120.015 0)
			(effects
				(font
					(size 1.27 1.27)
					(thickness 0.15)
				)
				(justify left bottom)
				(hide yes)
			)
		)
		(property "Author" "Antmicro"
			(at 379.73 120.015 0)
			(effects
				(font
					(size 1.27 1.27)
					(thickness 0.15)
				)
				(justify left bottom)
				(hide yes)
			)
		)
		(property "License" "Apache-2.0"
			(at 382.27 120.015 0)
			(effects
				(font
					(size 1.27 1.27)
					(thickness 0.15)
				)
				(justify left bottom)
				(hide yes)
			)
		)
		(pin "1"
		)
		(instances
			(project "gmsl-deserializer"
				(path ""
					(reference "TP27")
					(unit 1)
				)
			)
		)
	)
	(symbol
		(lib_id "antmicroTransistorsFETsMOSFETsSingle:DMG1012T-7")
		(at 382.27 71.12 0)
		(unit 1)
		(exclude_from_sim no)
		(in_bom yes)
		(on_board yes)
		(dnp no)
		(fields_autoplaced yes)
		(property "Reference" "Q5"
			(at 392.43 67.31 0)
			(effects
				(font
					(size 1.27 1.27)
					(thickness 0.15)
				)
				(justify left)
			)
		)
		(property "Value" "DMG1012T-7"
			(at 392.43 74.93 0)
			(effects
				(font
					(size 1.27 1.27)
					(thickness 0.15)
				)
				(justify left bottom)
				(hide yes)
			)
		)
		(property "Footprint" "antmicro-footprints:SOT-523"
			(at 392.43 77.47 0)
			(effects
				(font
					(size 1.27 1.27)
					(thickness 0.15)
				)
				(justify left bottom)
				(hide yes)
			)
		)
		(property "Datasheet" "https://www.diodes.com/assets/Datasheets/ds31783.pdf"
			(at 392.43 80.01 0)
			(effects
				(font
					(size 1.27 1.27)
					(thickness 0.15)
				)
				(justify left bottom)
				(hide yes)
			)
		)
		(property "Description" "Power MOSFET, N Channel, 20 V, 630 mA, 0.3 ohm, SOT-523, Surface Mount"
			(at 382.27 71.12 0)
			(effects
				(font
					(size 1.27 1.27)
				)
				(hide yes)
			)
		)
		(property "MPN" "DMG1012T-7"
			(at 392.43 69.85 0)
			(effects
				(font
					(size 1.27 1.27)
					(thickness 0.15)
				)
				(justify left)
			)
		)
		(property "Manufacturer" "Diodes Incorporated"
			(at 392.43 72.39 0)
			(effects
				(font
					(size 1.27 1.27)
					(thickness 0.15)
				)
				(justify left bottom)
				(hide yes)
			)
		)
		(property "Author" "Antmicro"
			(at 392.43 82.55 0)
			(effects
				(font
					(size 1.27 1.27)
					(thickness 0.15)
				)
				(justify left bottom)
				(hide yes)
			)
		)
		(property "License" "Apache-2.0"
			(at 392.43 85.09 0)
			(effects
				(font
					(size 1.27 1.27)
					(thickness 0.15)
				)
				(justify left bottom)
				(hide yes)
			)
		)
		(property "Public" ""
			(at 402.59 78.74 0)
			(effects
				(font
					(size 1.27 1.27)
				)
				(justify left bottom)
				(hide yes)
			)
		)
		(pin "2"
		)
		(pin "3"
		)
		(pin "1"
		)
		(instances
			(project "gmsl-deserializer"
				(path ""
					(reference "Q5")
					(unit 1)
				)
			)
		)
	)
	(symbol
		(lib_id "antmicroCapacitors0402:C_100n_0402")
		(at 81.28 96.52 90)
		(unit 1)
		(exclude_from_sim no)
		(in_bom yes)
		(on_board yes)
		(dnp no)
		(property "Reference" "C7"
			(at 81.915 92.075 90)
			(effects
				(font
					(size 1.27 1.27)
					(thickness 0.15)
				)
				(justify right)
			)
		)
		(property "Value" "C_100n_0402"
			(at 91.44 76.2 0)
			(effects
				(font
					(size 1.27 1.27)
					(thickness 0.15)
				)
				(justify left bottom)
				(hide yes)
			)
		)
		(property "Footprint" "antmicro-footprints:C_0402_1005Metric"
			(at 93.98 76.2 0)
			(effects
				(font
					(size 1.27 1.27)
					(thickness 0.15)
				)
				(justify left bottom)
				(hide yes)
			)
		)
		(property "Datasheet" "https://www.murata.com/products/productdetail?partno=GRM155R61H104KE14%23"
			(at 96.52 76.2 0)
			(effects
				(font
					(size 1.27 1.27)
					(thickness 0.15)
				)
				(justify left bottom)
				(hide yes)
			)
		)
		(property "Description" "SMD Multilayer Ceramic Capacitor, 0.1 µF, 50 V, 0402 [1005 Metric], ± 10%, X5R, GRM Series"
			(at 81.28 96.52 0)
			(effects
				(font
					(size 1.27 1.27)
				)
				(hide yes)
			)
		)
		(property "MPN" "GRM155R61H104KE14D"
			(at 99.06 76.2 0)
			(effects
				(font
					(size 1.27 1.27)
					(thickness 0.15)
				)
				(justify left bottom)
				(hide yes)
			)
		)
		(property "Manufacturer" "Murata"
			(at 101.6 76.2 0)
			(effects
				(font
					(size 1.27 1.27)
					(thickness 0.15)
				)
				(justify left bottom)
				(hide yes)
			)
		)
		(property "License" "Apache-2.0"
			(at 104.14 76.2 0)
			(effects
				(font
					(size 1.27 1.27)
					(thickness 0.15)
				)
				(justify left bottom)
				(hide yes)
			)
		)
		(property "Author" "Antmicro"
			(at 106.68 76.2 0)
			(effects
				(font
					(size 1.27 1.27)
					(thickness 0.15)
				)
				(justify left bottom)
				(hide yes)
			)
		)
		(property "Val" "100n"
			(at 81.915 95.885 90)
			(effects
				(font
					(size 1.27 1.27)
					(thickness 0.15)
				)
				(justify right)
			)
		)
		(property "Voltage" "50V"
			(at 109.22 76.2 0)
			(effects
				(font
					(size 1.27 1.27)
				)
				(justify left bottom)
				(hide yes)
			)
		)
		(property "Dielectric" "X5R"
			(at 111.76 76.2 0)
			(effects
				(font
					(size 1.27 1.27)
				)
				(justify left bottom)
				(hide yes)
			)
		)
		(pin "1"
		)
		(pin "2"
		)
		(instances
			(project "gmsl-deserializer"
				(path ""
					(reference "C7")
					(unit 1)
				)
			)
		)
	)
	(symbol
		(lib_id "antmicroCapacitors0603:C_10u_25V_0603")
		(at 394.97 224.79 270)
		(mirror x)
		(unit 1)
		(exclude_from_sim no)
		(in_bom yes)
		(on_board yes)
		(dnp no)
		(property "Reference" "C60"
			(at 397.51 220.98 90)
			(effects
				(font
					(size 1.27 1.27)
					(thickness 0.15)
				)
				(justify left)
			)
		)
		(property "Value" "C_10u_25V_0603"
			(at 384.81 204.47 0)
			(effects
				(font
					(size 1.27 1.27)
					(thickness 0.15)
				)
				(justify left bottom)
				(hide yes)
			)
		)
		(property "Footprint" "antmicro-footprints:C_0603_1608Metric"
			(at 382.27 204.47 0)
			(effects
				(font
					(size 1.27 1.27)
					(thickness 0.15)
				)
				(justify left bottom)
				(hide yes)
			)
		)
		(property "Datasheet" "https://product.tdk.com/en/search/capacitor/ceramic/mlcc/info?part_no=C1608X5R1E106M080AC"
			(at 379.73 204.47 0)
			(effects
				(font
					(size 1.27 1.27)
					(thickness 0.15)
				)
				(justify left bottom)
				(hide yes)
			)
		)
		(property "Description" "SMD Multilayer Ceramic Capacitor, 10 µF, 25 V, 0603 [1608 Metric], ± 20%, X5R, C"
			(at 394.97 224.79 0)
			(effects
				(font
					(size 1.27 1.27)
				)
				(hide yes)
			)
		)
		(property "MPN" "C1608X5R1E106M080AC"
			(at 377.19 204.47 0)
			(effects
				(font
					(size 1.27 1.27)
					(thickness 0.15)
				)
				(justify left bottom)
				(hide yes)
			)
		)
		(property "Manufacturer" "TDK"
			(at 374.65 204.47 0)
			(effects
				(font
					(size 1.27 1.27)
					(thickness 0.15)
				)
				(justify left bottom)
				(hide yes)
			)
		)
		(property "License" "Apache-2.0"
			(at 372.11 204.47 0)
			(effects
				(font
					(size 1.27 1.27)
					(thickness 0.15)
				)
				(justify left bottom)
				(hide yes)
			)
		)
		(property "Author" "Antmicro"
			(at 369.57 204.47 0)
			(effects
				(font
					(size 1.27 1.27)
					(thickness 0.15)
				)
				(justify left bottom)
				(hide yes)
			)
		)
		(property "Val" "10u"
			(at 401.32 223.52 90)
			(effects
				(font
					(size 1.27 1.27)
					(thickness 0.15)
				)
				(justify right)
			)
		)
		(property "Voltage" "25V"
			(at 367.03 204.47 0)
			(effects
				(font
					(size 1.27 1.27)
				)
				(justify left bottom)
				(hide yes)
			)
		)
		(property "Dielectric" ""
			(at 364.49 204.47 0)
			(effects
				(font
					(size 1.27 1.27)
				)
				(justify left bottom)
				(hide yes)
			)
		)
		(pin "1"
		)
		(pin "2"
		)
		(instances
			(project "gmsl-deserializer"
				(path ""
					(reference "C60")
					(unit 1)
				)
			)
		)
	)
	(symbol
		(lib_id "antmicroFixedInductors:L_470n_1A_Coilcraft-PFL1609")
		(at 157.48 62.23 0)
		(unit 1)
		(exclude_from_sim no)
		(in_bom yes)
		(on_board yes)
		(dnp no)
		(fields_autoplaced yes)
		(property "Reference" "L13"
			(at 160.02 57.15 0)
			(effects
				(font
					(size 1.27 1.27)
					(thickness 0.15)
				)
			)
		)
		(property "Value" "L_470n_1A_Coilcraft-PFL1609"
			(at 171.45 64.77 0)
			(effects
				(font
					(size 1.27 1.27)
					(thickness 0.15)
				)
				(justify left bottom)
				(hide yes)
			)
		)
		(property "Footprint" "antmicro-footprints:L_Coilcraft-PFL1609"
			(at 171.45 69.85 0)
			(effects
				(font
					(size 1.27 1.27)
					(thickness 0.15)
				)
				(justify left bottom)
				(hide yes)
			)
		)
		(property "Datasheet" "https://www.coilcraft.com/getmedia/2f4cd442-d64d-4413-a518-12fcfd03318d/pfl1609.pdf"
			(at 171.45 72.39 0)
			(effects
				(font
					(size 1.27 1.27)
					(thickness 0.15)
				)
				(justify left bottom)
				(hide yes)
			)
		)
		(property "Description" "Power Inductor (SMT), 6.8 µH, 9.2 A, Shielded, 12.8 A, XAL7070"
			(at 157.48 62.23 0)
			(effects
				(font
					(size 1.27 1.27)
				)
				(hide yes)
			)
		)
		(property "Val" "470n/0.99A"
			(at 160.02 59.69 0)
			(effects
				(font
					(size 1.27 1.27)
					(thickness 0.15)
				)
			)
		)
		(property "Manufacturer" "Coilcraft"
			(at 171.45 74.93 0)
			(effects
				(font
					(size 1.27 1.27)
					(thickness 0.15)
				)
				(justify left bottom)
				(hide yes)
			)
		)
		(property "MPN" "PFL1609-471"
			(at 171.45 77.47 0)
			(effects
				(font
					(size 1.27 1.27)
					(thickness 0.15)
				)
				(justify left bottom)
				(hide yes)
			)
		)
		(property "ISat" "0.99 A"
			(at 171.45 78.74 0)
			(effects
				(font
					(size 1.27 1.27)
				)
				(justify left)
				(hide yes)
			)
		)
		(property "IMax" "1 A"
			(at 171.45 82.55 0)
			(effects
				(font
					(size 1.27 1.27)
					(thickness 0.15)
				)
				(justify left bottom)
				(hide yes)
			)
		)
		(property "Size" "1.07x1.8"
			(at 171.45 85.09 0)
			(effects
				(font
					(size 1.27 1.27)
					(thickness 0.15)
				)
				(justify left bottom)
				(hide yes)
			)
		)
		(property "Author" "Antmicro"
			(at 171.45 87.63 0)
			(effects
				(font
					(size 1.27 1.27)
					(thickness 0.15)
				)
				(justify left bottom)
				(hide yes)
			)
		)
		(property "License" "Apache-2.0"
			(at 171.45 90.17 0)
			(effects
				(font
					(size 1.27 1.27)
					(thickness 0.15)
				)
				(justify left bottom)
				(hide yes)
			)
		)
		(pin "1"
		)
		(pin "2"
		)
		(instances
			(project "gmsl-deserializer"
				(path ""
					(reference "L13")
					(unit 1)
				)
			)
		)
	)
	(symbol
		(lib_id "antmicropower:GND")
		(at 81.28 97.79 0)
		(unit 1)
		(exclude_from_sim no)
		(in_bom yes)
		(on_board yes)
		(dnp no)
		(property "Reference" "#PWR025"
			(at 90.17 100.33 0)
			(effects
				(font
					(size 1.27 1.27)
					(thickness 0.15)
				)
				(justify left bottom)
				(hide yes)
			)
		)
		(property "Value" "GND"
			(at 81.28 101.6 0)
			(effects
				(font
					(size 1.27 1.27)
					(thickness 0.15)
				)
			)
		)
		(property "Footprint" ""
			(at 90.17 105.41 0)
			(effects
				(font
					(size 1.27 1.27)
					(thickness 0.15)
				)
				(justify left bottom)
				(hide yes)
			)
		)
		(property "Datasheet" ""
			(at 90.17 110.49 0)
			(effects
				(font
					(size 1.27 1.27)
					(thickness 0.15)
				)
				(justify left bottom)
				(hide yes)
			)
		)
		(property "Description" ""
			(at 81.28 97.79 0)
			(effects
				(font
					(size 1.27 1.27)
				)
				(hide yes)
			)
		)
		(property "Author" "Antmicro"
			(at 90.17 105.41 0)
			(effects
				(font
					(size 1.27 1.27)
					(thickness 0.15)
				)
				(justify left bottom)
				(hide yes)
			)
		)
		(property "License" "Apache-2.0"
			(at 90.17 107.95 0)
			(effects
				(font
					(size 1.27 1.27)
					(thickness 0.15)
				)
				(justify left bottom)
				(hide yes)
			)
		)
		(pin "1"
		)
		(instances
			(project "gmsl-deserializer"
				(path ""
					(reference "#PWR025")
					(unit 1)
				)
			)
		)
	)
	(symbol
		(lib_id "antmicroTestPoints:TP_0.75mm_SMD")
		(at 185.42 228.6 90)
		(unit 1)
		(exclude_from_sim no)
		(in_bom yes)
		(on_board yes)
		(dnp no)
		(property "Reference" "TP19"
			(at 184.15 223.52 90)
			(effects
				(font
					(size 1.27 1.27)
					(thickness 0.15)
				)
				(justify right)
			)
		)
		(property "Value" "TP_0.75mm_SMD"
			(at 189.23 217.805 0)
			(effects
				(font
					(size 1.27 1.27)
					(thickness 0.15)
				)
				(justify left bottom)
				(hide yes)
			)
		)
		(property "Footprint" "antmicro-footprints:TP_SMD_0.75mm"
			(at 191.77 217.805 0)
			(effects
				(font
					(size 1.27 1.27)
					(thickness 0.15)
				)
				(justify left bottom)
				(hide yes)
			)
		)
		(property "Datasheet" ""
			(at 198.12 210.82 0)
			(effects
				(font
					(size 1.27 1.27)
					(thickness 0.15)
				)
				(justify left bottom)
				(hide yes)
			)
		)
		(property "Description" "SMT test point"
			(at 185.42 228.6 0)
			(effects
				(font
					(size 1.27 1.27)
				)
				(hide yes)
			)
		)
		(property "MPN" ""
			(at 196.85 217.805 0)
			(effects
				(font
					(size 1.27 1.27)
					(thickness 0.15)
				)
				(justify left bottom)
				(hide yes)
			)
		)
		(property "Manufacturer" ""
			(at 191.77 217.805 0)
			(effects
				(font
					(size 1.27 1.27)
					(thickness 0.15)
				)
				(justify left bottom)
				(hide yes)
			)
		)
		(property "Author" "Antmicro"
			(at 194.31 217.805 0)
			(effects
				(font
					(size 1.27 1.27)
					(thickness 0.15)
				)
				(justify left bottom)
				(hide yes)
			)
		)
		(property "License" "Apache-2.0"
			(at 196.85 217.805 0)
			(effects
				(font
					(size 1.27 1.27)
					(thickness 0.15)
				)
				(justify left bottom)
				(hide yes)
			)
		)
		(pin "1"
		)
		(instances
			(project "gmsl-deserializer"
				(path ""
					(reference "TP19")
					(unit 1)
				)
			)
		)
	)
)
